FILE_TYPE = MACRO_DRAWING;
SET COLOR_WIRE YELLOW;
SET COLOR_PROP ORANGE;
SET COLOR_DOT WHITE;
SET COLOR_ARC YELLOW;
SET COLOR_BODY GREEN;
SET COLOR_NOTE PURPLE;
SET PROP_DISPLAY VALUE;
SET PAGE_NUMBER P143;
FORCEADD UNIVERSAL_POWER..1
(-1875 5725);
FORCEPROP 3 LASTPIN (-1875 5675) SIG_NAME P3V3_STBY\g
J 0
(-1865 5685);
DISPLAY 0.659574 (-1865 5685);
PAINT MONO (-1865 5685);
DISPLAY INVISIBLE (-1865 5685);
FORCEPROP 1 LAST HDL_POWER P3V3_STBY
J 1
(-1875 5775);
DISPLAY 0.489362 (-1875 5775);
PAINT GREEN (-1875 5775);
FORCEPROP 1 LAST PATH I1
J 0
(-1825 5750);
DISPLAY 0.872340 (-1825 5750);
PAINT AQUA (-1825 5750);
DISPLAY INVISIBLE (-1825 5750);
FORCEPROP 2 LAST CDS_LIB pure_quanta_power
J 0
(-1875 5725);
DISPLAY INVISIBLE (-1875 5725);
FORCEPROP 2 LAST BOM_COST OCP3.0 
J 0
(-1875 5825);
DISPLAY 0.680851 (-1875 5825);
DISPLAY INVISIBLE (-1875 5825);
FORCEADD UNIVERSAL_POWER..1
(-4100 4150);
FORCEPROP 3 LASTPIN (-4100 4100) SIG_NAME P3V3_STBY\g
J 0
(-4090 4110);
DISPLAY 0.659574 (-4090 4110);
PAINT MONO (-4090 4110);
DISPLAY INVISIBLE (-4090 4110);
FORCEPROP 1 LAST HDL_POWER P3V3_STBY
J 1
(-4100 4200);
DISPLAY 0.489362 (-4100 4200);
PAINT GREEN (-4100 4200);
FORCEPROP 1 LAST PATH I10
J 0
(-4050 4175);
DISPLAY 0.872340 (-4050 4175);
PAINT AQUA (-4050 4175);
DISPLAY INVISIBLE (-4050 4175);
FORCEPROP 2 LAST CDS_LIB pure_quanta_power
J 0
(-4100 4150);
DISPLAY INVISIBLE (-4100 4150);
FORCEPROP 2 LAST BOM_COST OCP3.0 
J 0
(-4100 4250);
DISPLAY 0.680851 (-4100 4250);
DISPLAY INVISIBLE (-4100 4250);
FORCEADD Q_RES..2
(-4100 3800);
FORCEPROP 1 LAST LOCATION R947
J 0
(-4055 3925);
DISPLAY 0.489362 (-4055 3925);
PAINT SKYBLUE (-4055 3925);
FORCEPROP 0 LAST $SEC 1
J 0
(-4050 3975);
DISPLAY 0.680851 (-4050 3975);
PAINT MONO (-4050 3975);
DISPLAY INVISIBLE (-4050 3975);
FORCEPROP 0 LAST CDS_SEC 1
J 0
(-4050 3975);
DISPLAY 0.680851 (-4050 3975);
DISPLAY INVISIBLE (-4050 3975);
FORCEPROP 1 LASTPIN (-4100 3900) $PN 1
J 0
(-4095 3862);
DISPLAY 0.489362 (-4095 3862);
PAINT MONO (-4095 3862);
FORCEPROP 1 LASTPIN (-4100 3700) $PN 2
J 0
(-4095 3710);
DISPLAY 0.489362 (-4095 3710);
PAINT MONO (-4095 3710);
FORCEPROP 1 LAST VALUE 4.7K
J 0
(-4055 3875);
DISPLAY 0.489362 (-4055 3875);
PAINT SKYBLUE (-4055 3875);
FORCEPROP 1 LAST TOLERANCE 5%
J 0
(-4055 3825);
DISPLAY 0.489362 (-4055 3825);
PAINT SKYBLUE (-4055 3825);
FORCEPROP 1 LAST MATERIAL CHIP
J 0
(-4060 3725);
DISPLAY 0.489362 (-4060 3725);
PAINT SKYBLUE (-4060 3725);
FORCEPROP 1 LAST WATTAGE 1/16W
J 0
(-4060 3775);
DISPLAY 0.489362 (-4060 3775);
PAINT SKYBLUE (-4060 3775);
FORCEPROP 1 LAST PACK_TYPE 0402LF
J 0
(-4060 3625);
DISPLAY 0.489362 (-4060 3625);
PAINT SKYBLUE (-4060 3625);
DISPLAY INVISIBLE (-4060 3625);
FORCEPROP 1 LAST PART_NUMBER TMP_QCS24702JB38
J 0
(-4060 3675);
DISPLAY 0.489362 (-4060 3675);
PAINT SKYBLUE (-4060 3675);
DISPLAY INVISIBLE (-4060 3675);
FORCEPROP 1 LAST PATH I11
J 0
(-4050 3975);
DISPLAY 0.978723 (-4050 3975);
PAINT WHITE (-4050 3975);
DISPLAY INVISIBLE (-4050 3975);
FORCEPROP 2 LAST BOM_COST OCP3.0 
J 0
(-4050 3975);
DISPLAY 0.680851 (-4050 3975);
DISPLAY INVISIBLE (-4050 3975);
FORCEPROP 2 LAST CDS_LIB pure_quanta
J 0
(-4100 3800);
DISPLAY INVISIBLE (-4100 3800);
FORCEADD GND..1
R 1
(-4150 3550);
FORCEPROP 3 LASTPIN (-4200 3550) SIG_NAME GND\g
J 0
(-4190 3560);
DISPLAY 0.659574 (-4190 3560);
PAINT MONO (-4190 3560);
DISPLAY INVISIBLE (-4190 3560);
FORCEPROP 1 LAST HDL_POWER GND
R 1
J 0
(-4300 3550);
DISPLAY 0.851064 (-4300 3550);
PAINT GREEN (-4300 3550);
DISPLAY INVISIBLE (-4300 3550);
FORCEPROP 1 LAST PATH I12
R 1
J 0
(-4150 3625);
DISPLAY 0.872340 (-4150 3625);
PAINT AQUA (-4150 3625);
DISPLAY INVISIBLE (-4150 3625);
FORCEPROP 2 LAST CDS_LIB pure_quanta_power
J 0
(-4150 3550);
DISPLAY INVISIBLE (-4150 3550);
FORCEPROP 2 LAST BOM_COST MEM
R 1
J 0
(-4225 3450);
DISPLAY 0.808511 (-4225 3450);
DISPLAY INVISIBLE (-4225 3450);
FORCEPROP 1 LAST SIZE 1B
R 1
J 0
(-4100 3625);
DISPLAY 0.851064 (-4100 3625);
PAINT GREEN (-4100 3625);
DISPLAY INVISIBLE (-4100 3625);
FORCEADD GND..1
R 5
(-4775 5175);
FORCEPROP 3 LASTPIN (-4725 5175) SIG_NAME GND\g
J 0
(-4715 5185);
DISPLAY 0.659574 (-4715 5185);
PAINT MONO (-4715 5185);
DISPLAY INVISIBLE (-4715 5185);
FORCEPROP 1 LAST HDL_POWER GND
R 3
J 0
(-4625 5175);
DISPLAY 0.851064 (-4625 5175);
PAINT GREEN (-4625 5175);
DISPLAY INVISIBLE (-4625 5175);
FORCEPROP 1 LAST PATH I13
R 3
J 0
(-4775 5100);
DISPLAY 0.872340 (-4775 5100);
PAINT AQUA (-4775 5100);
DISPLAY INVISIBLE (-4775 5100);
FORCEPROP 2 LAST CDS_LIB pure_quanta_power
J 0
(-4775 5175);
DISPLAY INVISIBLE (-4775 5175);
FORCEPROP 1 LAST SIZE 1B
R 3
J 0
(-4825 5100);
DISPLAY 0.851064 (-4825 5100);
PAINT GREEN (-4825 5100);
DISPLAY INVISIBLE (-4825 5100);
FORCEPROP 2 LAST BOM_COST MEM
R 3
J 0
(-4700 5275);
DISPLAY 0.808511 (-4700 5275);
DISPLAY INVISIBLE (-4700 5275);
FORCEADD UNIVERSAL_POWER..1
(-4950 5775);
FORCEPROP 3 LASTPIN (-4950 5725) SIG_NAME P3V3_STBY\g
J 0
(-4940 5735);
DISPLAY 0.659574 (-4940 5735);
PAINT MONO (-4940 5735);
DISPLAY INVISIBLE (-4940 5735);
FORCEPROP 1 LAST HDL_POWER P3V3_STBY
J 1
(-4950 5825);
DISPLAY 0.489362 (-4950 5825);
PAINT GREEN (-4950 5825);
FORCEPROP 1 LAST PATH I14
J 0
(-4900 5800);
DISPLAY 0.872340 (-4900 5800);
PAINT AQUA (-4900 5800);
DISPLAY INVISIBLE (-4900 5800);
FORCEPROP 2 LAST CDS_LIB pure_quanta_power
J 0
(-4950 5775);
DISPLAY INVISIBLE (-4950 5775);
FORCEPROP 2 LAST BOM_COST OCP3.0 
J 0
(-4950 5875);
DISPLAY 0.680851 (-4950 5875);
DISPLAY INVISIBLE (-4950 5875);
FORCEADD Q_RES..2
(-4950 5425);
FORCEPROP 1 LAST LOCATION R944
J 0
(-4905 5550);
DISPLAY 0.489362 (-4905 5550);
PAINT SKYBLUE (-4905 5550);
FORCEPROP 0 LAST $SEC 1
J 0
(-4900 5600);
DISPLAY 0.680851 (-4900 5600);
PAINT MONO (-4900 5600);
DISPLAY INVISIBLE (-4900 5600);
FORCEPROP 0 LAST CDS_SEC 1
J 0
(-4900 5600);
DISPLAY 0.680851 (-4900 5600);
DISPLAY INVISIBLE (-4900 5600);
FORCEPROP 1 LASTPIN (-4950 5525) $PN 1
J 0
(-4945 5487);
DISPLAY 0.489362 (-4945 5487);
PAINT MONO (-4945 5487);
FORCEPROP 1 LASTPIN (-4950 5325) $PN 2
J 0
(-4945 5335);
DISPLAY 0.489362 (-4945 5335);
PAINT MONO (-4945 5335);
FORCEPROP 1 LAST VALUE 4.7K
J 0
(-4905 5500);
DISPLAY 0.489362 (-4905 5500);
PAINT SKYBLUE (-4905 5500);
FORCEPROP 1 LAST TOLERANCE 5%
J 0
(-4905 5450);
DISPLAY 0.489362 (-4905 5450);
PAINT SKYBLUE (-4905 5450);
FORCEPROP 1 LAST MATERIAL CHIP
J 0
(-4910 5350);
DISPLAY 0.489362 (-4910 5350);
PAINT SKYBLUE (-4910 5350);
FORCEPROP 1 LAST WATTAGE 1/16W
J 0
(-4910 5400);
DISPLAY 0.489362 (-4910 5400);
PAINT SKYBLUE (-4910 5400);
FORCEPROP 1 LAST PACK_TYPE 0402LF
J 0
(-4910 5250);
DISPLAY 0.489362 (-4910 5250);
PAINT SKYBLUE (-4910 5250);
DISPLAY INVISIBLE (-4910 5250);
FORCEPROP 1 LAST PART_NUMBER TMP_QCS24702JB38
J 0
(-4910 5300);
DISPLAY 0.489362 (-4910 5300);
PAINT SKYBLUE (-4910 5300);
DISPLAY INVISIBLE (-4910 5300);
FORCEPROP 1 LAST PATH I15
J 0
(-4900 5600);
DISPLAY 0.978723 (-4900 5600);
PAINT WHITE (-4900 5600);
DISPLAY INVISIBLE (-4900 5600);
FORCEPROP 2 LAST BOM_COST OCP3.0 
J 0
(-4900 5600);
DISPLAY 0.680851 (-4900 5600);
DISPLAY INVISIBLE (-4900 5600);
FORCEPROP 2 LAST CDS_LIB pure_quanta
J 0
(-4950 5425);
DISPLAY INVISIBLE (-4950 5425);
FORCEADD MOSFET_DUAL_6P..1
(-4400 5125);
FORCEPROP 1 LAST LOCATION Q2
J 0
(-4547 5334);
DISPLAY 0.489362 (-4547 5334);
PAINT SKYBLUE (-4547 5334);
FORCEPROP 0 LAST $SEC 1
J 0
(-4525 5475);
DISPLAY 0.680851 (-4525 5475);
PAINT MONO (-4525 5475);
DISPLAY INVISIBLE (-4525 5475);
FORCEPROP 0 LAST CDS_SEC 1
J 0
(-4525 5475);
DISPLAY 0.680851 (-4525 5475);
DISPLAY INVISIBLE (-4525 5475);
FORCEPROP 0 LASTPIN (-4700 5075) $PN 6
J 2
(-4710 5085);
DISPLAY 0.489362 (-4710 5085);
PAINT MONO (-4710 5085);
FORCEPROP 0 LASTPIN (-4100 5075) $PN 3
J 0
(-4090 5085);
DISPLAY 0.489362 (-4090 5085);
PAINT MONO (-4090 5085);
FORCEPROP 0 LASTPIN (-4700 5125) $PN 2
J 2
(-4710 5135);
DISPLAY 0.489362 (-4710 5135);
PAINT MONO (-4710 5135);
FORCEPROP 0 LASTPIN (-4100 5125) $PN 5
J 0
(-4090 5135);
DISPLAY 0.489362 (-4090 5135);
PAINT MONO (-4090 5135);
FORCEPROP 0 LASTPIN (-4700 5175) $PN 1
J 2
(-4710 5185);
DISPLAY 0.489362 (-4710 5185);
PAINT MONO (-4710 5185);
FORCEPROP 0 LASTPIN (-4100 5175) $PN 4
J 0
(-4090 5185);
DISPLAY 0.489362 (-4090 5185);
PAINT MONO (-4090 5185);
FORCEPROP 1 LAST PART_NUMBER BAM70020047
J 0
(-4547 5292);
DISPLAY 0.489362 (-4547 5292);
PAINT SKYBLUE (-4547 5292);
FORCEPROP 2 LAST VALUE 2N7002KDW
J 0
(-4525 5375);
DISPLAY 0.489362 (-4525 5375);
PAINT SKYBLUE (-4525 5375);
FORCEPROP 1 LAST MATERIAL IC
J 0
(-4547 5248);
DISPLAY 0.489362 (-4547 5248);
PAINT SKYBLUE (-4547 5248);
FORCEPROP 2 LAST PART_TYPE SMLF
J 0
(-4525 5425);
DISPLAY 0.680851 (-4525 5425);
FORCEPROP 1 LAST PATH I16
J 0
(-4400 5125);
DISPLAY 0.723404 (-4400 5125);
PAINT GREEN (-4400 5125);
DISPLAY INVISIBLE (-4400 5125);
FORCEPROP 1 LAST NEEDS_NO_SIZE TRUE
J 0
(-4400 5124);
DISPLAY 0.468085 (-4400 5124);
PAINT GREEN (-4400 5124);
DISPLAY INVISIBLE (-4400 5124);
FORCEPROP 1 LAST CDS_LMAN_SYM_OUTLINE -150,100,150,-100
J 0
(-4400 5125);
DISPLAY 0.468085 (-4400 5125);
PAINT GREEN (-4400 5125);
DISPLAY INVISIBLE (-4400 5125);
FORCEPROP 2 LAST CDS_LIB pure_quanta
J 0
(-4400 5125);
DISPLAY INVISIBLE (-4400 5125);
FORCEADD UNIVERSAL_POWER..1
(-5100 4150);
FORCEPROP 3 LASTPIN (-5100 4100) SIG_NAME P3V3_STBY\g
J 0
(-5090 4110);
DISPLAY 0.659574 (-5090 4110);
PAINT MONO (-5090 4110);
DISPLAY INVISIBLE (-5090 4110);
FORCEPROP 1 LAST HDL_POWER P3V3_STBY
J 1
(-5100 4200);
DISPLAY 0.489362 (-5100 4200);
PAINT GREEN (-5100 4200);
FORCEPROP 1 LAST PATH I17
J 0
(-5050 4175);
DISPLAY 0.872340 (-5050 4175);
PAINT AQUA (-5050 4175);
DISPLAY INVISIBLE (-5050 4175);
FORCEPROP 2 LAST CDS_LIB pure_quanta_power
J 0
(-5100 4150);
DISPLAY INVISIBLE (-5100 4150);
FORCEPROP 2 LAST BOM_COST OCP3.0 
J 0
(-5100 4250);
DISPLAY 0.680851 (-5100 4250);
DISPLAY INVISIBLE (-5100 4250);
FORCEADD Q_RES..2
(-5100 3800);
FORCEPROP 1 LAST LOCATION R945
J 0
(-5055 3925);
DISPLAY 0.489362 (-5055 3925);
PAINT SKYBLUE (-5055 3925);
FORCEPROP 0 LAST $SEC 1
J 0
(-5050 3975);
DISPLAY 0.680851 (-5050 3975);
PAINT MONO (-5050 3975);
DISPLAY INVISIBLE (-5050 3975);
FORCEPROP 0 LAST CDS_SEC 1
J 0
(-5050 3975);
DISPLAY 0.680851 (-5050 3975);
DISPLAY INVISIBLE (-5050 3975);
FORCEPROP 1 LASTPIN (-5100 3900) $PN 1
J 0
(-5095 3862);
DISPLAY 0.489362 (-5095 3862);
PAINT MONO (-5095 3862);
FORCEPROP 1 LASTPIN (-5100 3700) $PN 2
J 0
(-5095 3710);
DISPLAY 0.489362 (-5095 3710);
PAINT MONO (-5095 3710);
FORCEPROP 1 LAST MATERIAL CHIP
J 0
(-5060 3725);
DISPLAY 0.489362 (-5060 3725);
PAINT SKYBLUE (-5060 3725);
FORCEPROP 1 LAST VALUE 4.7K
J 0
(-5055 3875);
DISPLAY 0.489362 (-5055 3875);
PAINT SKYBLUE (-5055 3875);
FORCEPROP 1 LAST TOLERANCE 5%
J 0
(-5055 3825);
DISPLAY 0.489362 (-5055 3825);
PAINT SKYBLUE (-5055 3825);
FORCEPROP 1 LAST WATTAGE 1/16W
J 0
(-5060 3775);
DISPLAY 0.489362 (-5060 3775);
PAINT SKYBLUE (-5060 3775);
FORCEPROP 1 LAST PACK_TYPE 0402LF
J 0
(-5060 3625);
DISPLAY 0.489362 (-5060 3625);
PAINT SKYBLUE (-5060 3625);
DISPLAY INVISIBLE (-5060 3625);
FORCEPROP 1 LAST PART_NUMBER TMP_QCS24702JB38
J 0
(-5060 3675);
DISPLAY 0.489362 (-5060 3675);
PAINT SKYBLUE (-5060 3675);
DISPLAY INVISIBLE (-5060 3675);
FORCEPROP 1 LAST PATH I18
J 0
(-5050 3975);
DISPLAY 0.978723 (-5050 3975);
PAINT WHITE (-5050 3975);
DISPLAY INVISIBLE (-5050 3975);
FORCEPROP 2 LAST BOM_COST OCP3.0 
J 0
(-5050 3975);
DISPLAY 0.680851 (-5050 3975);
DISPLAY INVISIBLE (-5050 3975);
FORCEPROP 2 LAST CDS_LIB pure_quanta
J 0
(-5100 3800);
DISPLAY INVISIBLE (-5100 3800);
FORCEADD MOSFET_DUAL_6P..1
(-4550 3500);
FORCEPROP 1 LAST LOCATION Q11
J 0
(-4697 3709);
DISPLAY 0.489362 (-4697 3709);
PAINT SKYBLUE (-4697 3709);
FORCEPROP 0 LAST $SEC 1
J 0
(-4675 3850);
DISPLAY 0.680851 (-4675 3850);
PAINT MONO (-4675 3850);
DISPLAY INVISIBLE (-4675 3850);
FORCEPROP 0 LAST CDS_SEC 1
J 0
(-4675 3850);
DISPLAY 0.680851 (-4675 3850);
DISPLAY INVISIBLE (-4675 3850);
FORCEPROP 0 LASTPIN (-4850 3450) $PN 6
J 2
(-4860 3460);
DISPLAY 0.489362 (-4860 3460);
PAINT MONO (-4860 3460);
FORCEPROP 0 LASTPIN (-4250 3450) $PN 3
J 0
(-4240 3460);
DISPLAY 0.489362 (-4240 3460);
PAINT MONO (-4240 3460);
FORCEPROP 0 LASTPIN (-4850 3500) $PN 2
J 2
(-4860 3510);
DISPLAY 0.489362 (-4860 3510);
PAINT MONO (-4860 3510);
FORCEPROP 0 LASTPIN (-4250 3500) $PN 5
J 0
(-4240 3510);
DISPLAY 0.489362 (-4240 3510);
PAINT MONO (-4240 3510);
FORCEPROP 0 LASTPIN (-4850 3550) $PN 1
J 2
(-4860 3560);
DISPLAY 0.489362 (-4860 3560);
PAINT MONO (-4860 3560);
FORCEPROP 0 LASTPIN (-4250 3550) $PN 4
J 0
(-4240 3560);
DISPLAY 0.489362 (-4240 3560);
PAINT MONO (-4240 3560);
FORCEPROP 1 LAST PART_NUMBER BAM70020047
J 0
(-4697 3667);
DISPLAY 0.489362 (-4697 3667);
PAINT SKYBLUE (-4697 3667);
FORCEPROP 2 LAST VALUE 2N7002KDW
J 0
(-4675 3750);
DISPLAY 0.489362 (-4675 3750);
PAINT SKYBLUE (-4675 3750);
FORCEPROP 1 LAST MATERIAL IC
J 0
(-4697 3623);
DISPLAY 0.489362 (-4697 3623);
PAINT SKYBLUE (-4697 3623);
FORCEPROP 2 LAST PART_TYPE SMLF
J 0
(-4675 3800);
DISPLAY 0.680851 (-4675 3800);
FORCEPROP 1 LAST PATH I19
J 0
(-4550 3500);
DISPLAY 0.723404 (-4550 3500);
PAINT GREEN (-4550 3500);
DISPLAY INVISIBLE (-4550 3500);
FORCEPROP 1 LAST NEEDS_NO_SIZE TRUE
J 0
(-4550 3499);
DISPLAY 0.468085 (-4550 3499);
PAINT GREEN (-4550 3499);
DISPLAY INVISIBLE (-4550 3499);
FORCEPROP 1 LAST CDS_LMAN_SYM_OUTLINE -150,100,150,-100
J 0
(-4550 3500);
DISPLAY 0.468085 (-4550 3500);
PAINT GREEN (-4550 3500);
DISPLAY INVISIBLE (-4550 3500);
FORCEPROP 2 LAST CDS_LIB pure_quanta
J 0
(-4550 3500);
DISPLAY INVISIBLE (-4550 3500);
FORCEADD UNIVERSAL_POWER..1
(-2125 4100);
FORCEPROP 3 LASTPIN (-2125 4050) SIG_NAME P3V3_STBY\g
J 0
(-2115 4060);
DISPLAY 0.659574 (-2115 4060);
PAINT MONO (-2115 4060);
DISPLAY INVISIBLE (-2115 4060);
FORCEPROP 1 LAST HDL_POWER P3V3_STBY
J 1
(-2125 4150);
DISPLAY 0.489362 (-2125 4150);
PAINT GREEN (-2125 4150);
FORCEPROP 1 LAST PATH I2
J 0
(-2075 4125);
DISPLAY 0.872340 (-2075 4125);
PAINT AQUA (-2075 4125);
DISPLAY INVISIBLE (-2075 4125);
FORCEPROP 2 LAST CDS_LIB pure_quanta_power
J 0
(-2125 4100);
DISPLAY INVISIBLE (-2125 4100);
FORCEPROP 2 LAST BOM_COST OCP3.0 
J 0
(-2125 4200);
DISPLAY 0.680851 (-2125 4200);
DISPLAY INVISIBLE (-2125 4200);
FORCEADD GND..1
R 5
(-4925 3550);
FORCEPROP 3 LASTPIN (-4875 3550) SIG_NAME GND\g
J 0
(-4865 3560);
DISPLAY 0.659574 (-4865 3560);
PAINT MONO (-4865 3560);
DISPLAY INVISIBLE (-4865 3560);
FORCEPROP 1 LAST HDL_POWER GND
R 3
J 0
(-4775 3550);
DISPLAY 0.851064 (-4775 3550);
PAINT GREEN (-4775 3550);
DISPLAY INVISIBLE (-4775 3550);
FORCEPROP 1 LAST PATH I20
R 3
J 0
(-4925 3475);
DISPLAY 0.872340 (-4925 3475);
PAINT AQUA (-4925 3475);
DISPLAY INVISIBLE (-4925 3475);
FORCEPROP 2 LAST CDS_LIB pure_quanta_power
J 0
(-4925 3550);
DISPLAY INVISIBLE (-4925 3550);
FORCEPROP 1 LAST SIZE 1B
R 3
J 0
(-4975 3475);
DISPLAY 0.851064 (-4975 3475);
PAINT GREEN (-4975 3475);
DISPLAY INVISIBLE (-4975 3475);
FORCEPROP 2 LAST BOM_COST MEM
R 3
J 0
(-4850 3650);
DISPLAY 0.808511 (-4850 3650);
DISPLAY INVISIBLE (-4850 3650);
FORCEADD Q_RES..1
(-5675 5125);
FORCEPROP 1 LAST LOCATION R935
J 0
(-5625 5125);
DISPLAY 0.489362 (-5625 5125);
PAINT SKYBLUE (-5625 5125);
FORCEPROP 0 LAST $SEC 1
J 0
(-5625 5175);
DISPLAY 0.680851 (-5625 5175);
PAINT MONO (-5625 5175);
DISPLAY INVISIBLE (-5625 5175);
FORCEPROP 0 LAST CDS_SEC 1
J 0
(-5625 5175);
DISPLAY 0.680851 (-5625 5175);
DISPLAY INVISIBLE (-5625 5175);
FORCEPROP 1 LASTPIN (-5775 5125) $PN 1
J 0
(-5763 5137);
DISPLAY 0.489362 (-5763 5137);
PAINT MONO (-5763 5137);
FORCEPROP 1 LASTPIN (-5575 5125) $PN 2
J 0
(-5613 5137);
DISPLAY 0.489362 (-5613 5137);
PAINT MONO (-5613 5137);
FORCEPROP 1 LAST VALUE 0
J 2
(-5800 5125);
DISPLAY 0.489362 (-5800 5125);
PAINT SKYBLUE (-5800 5125);
FORCEPROP 2 LAST ROOM RST_CPU0_PLD_TO_DIMM
J 2
(-5650 5225);
DISPLAY 0.744681 (-5650 5225);
PAINT RED (-5650 5225);
DISPLAY INVISIBLE (-5650 5225);
FORCEPROP 1 LAST PACK_TYPE 0402LF
J 2
(-5500 5050);
DISPLAY 0.489362 (-5500 5050);
PAINT SKYBLUE (-5500 5050);
DISPLAY INVISIBLE (-5500 5050);
FORCEPROP 1 LAST PART_NUMBER CS00002JB38
J 2
(-5575 5175);
DISPLAY 0.489362 (-5575 5175);
PAINT SKYBLUE (-5575 5175);
DISPLAY INVISIBLE (-5575 5175);
FORCEPROP 1 LAST TOLERANCE 5%
J 0
(-5800 5100);
DISPLAY 0.489362 (-5800 5100);
PAINT SKYBLUE (-5800 5100);
DISPLAY INVISIBLE (-5800 5100);
FORCEPROP 1 LAST MATERIAL CHIP
J 2
(-5500 5100);
DISPLAY 0.489362 (-5500 5100);
PAINT SKYBLUE (-5500 5100);
DISPLAY INVISIBLE (-5500 5100);
FORCEPROP 1 LAST WATTAGE 1/16W
J 2
(-5750 5050);
DISPLAY 0.489362 (-5750 5050);
PAINT SKYBLUE (-5750 5050);
DISPLAY INVISIBLE (-5750 5050);
FORCEPROP 1 LAST PATH I21
J 0
(-5725 5275);
DISPLAY 0.978723 (-5725 5275);
PAINT WHITE (-5725 5275);
DISPLAY INVISIBLE (-5725 5275);
FORCEPROP 2 LAST CDS_LIB pure_quanta
J 0
(-5675 5125);
DISPLAY INVISIBLE (-5675 5125);
FORCEPROP 2 LAST BOM_COST MEM
J 2
(-5650 5275);
DISPLAY 0.744681 (-5650 5275);
PAINT WHITE (-5650 5275);
DISPLAY INVISIBLE (-5650 5275);
FORCEADD Q_RES..1
(-5825 3500);
FORCEPROP 1 LAST LOCATION R936
J 0
(-5775 3450);
DISPLAY 0.489362 (-5775 3450);
PAINT SKYBLUE (-5775 3450);
FORCEPROP 0 LAST $SEC 1
J 0
(-5775 3550);
DISPLAY 0.680851 (-5775 3550);
PAINT MONO (-5775 3550);
DISPLAY INVISIBLE (-5775 3550);
FORCEPROP 0 LAST CDS_SEC 1
J 0
(-5775 3550);
DISPLAY 0.680851 (-5775 3550);
DISPLAY INVISIBLE (-5775 3550);
FORCEPROP 1 LASTPIN (-5925 3500) $PN 1
J 0
(-5913 3512);
DISPLAY 0.489362 (-5913 3512);
PAINT MONO (-5913 3512);
FORCEPROP 1 LASTPIN (-5725 3500) $PN 2
J 0
(-5763 3512);
DISPLAY 0.489362 (-5763 3512);
PAINT MONO (-5763 3512);
FORCEPROP 2 LASTPIN (-5725 3500) SIG_NAME FM_SMERR_BUF_R_LED_N
J 0
(-5660 3510);
DISPLAY 0.489362 (-5660 3510);
FORCEPROP 2 LASTPROP $XRERR UNIQUE?
J 0
(-5900 3510);
DISPLAY 0.638298 (-5900 3510);
PAINT MONO (-5900 3510);
DISPLAY INVISIBLE (-5900 3510);
FORCEPROP 1 LAST VALUE 0
J 2
(-5950 3500);
DISPLAY 0.489362 (-5950 3500);
PAINT SKYBLUE (-5950 3500);
FORCEPROP 2 LAST ROOM RST_CPU0_PLD_TO_DIMM
J 2
(-5800 3600);
DISPLAY 0.744681 (-5800 3600);
PAINT RED (-5800 3600);
DISPLAY INVISIBLE (-5800 3600);
FORCEPROP 1 LAST PACK_TYPE 0402LF
J 2
(-5650 3425);
DISPLAY 0.489362 (-5650 3425);
PAINT SKYBLUE (-5650 3425);
DISPLAY INVISIBLE (-5650 3425);
FORCEPROP 1 LAST PART_NUMBER CS00002JB38
J 2
(-5725 3550);
DISPLAY 0.489362 (-5725 3550);
PAINT SKYBLUE (-5725 3550);
DISPLAY INVISIBLE (-5725 3550);
FORCEPROP 1 LAST TOLERANCE 5%
J 0
(-5950 3475);
DISPLAY 0.489362 (-5950 3475);
PAINT SKYBLUE (-5950 3475);
DISPLAY INVISIBLE (-5950 3475);
FORCEPROP 1 LAST MATERIAL CHIP
J 2
(-5650 3475);
DISPLAY 0.489362 (-5650 3475);
PAINT SKYBLUE (-5650 3475);
DISPLAY INVISIBLE (-5650 3475);
FORCEPROP 1 LAST WATTAGE 1/16W
J 2
(-5900 3425);
DISPLAY 0.489362 (-5900 3425);
PAINT SKYBLUE (-5900 3425);
DISPLAY INVISIBLE (-5900 3425);
FORCEPROP 1 LAST PATH I22
J 0
(-5875 3650);
DISPLAY 0.978723 (-5875 3650);
PAINT WHITE (-5875 3650);
DISPLAY INVISIBLE (-5875 3650);
FORCEPROP 2 LAST CDS_LIB pure_quanta
J 0
(-5825 3500);
DISPLAY INVISIBLE (-5825 3500);
FORCEPROP 2 LAST BOM_COST MEM
J 2
(-5800 3650);
DISPLAY 0.744681 (-5800 3650);
PAINT WHITE (-5800 3650);
DISPLAY INVISIBLE (-5800 3650);
FORCEADD Q_CAP..1
(-7200 5450);
FORCEPROP 1 LAST LOCATION C218
J 0
(-7150 5550);
DISPLAY 0.489362 (-7150 5550);
PAINT SKYBLUE (-7150 5550);
FORCEPROP 0 LAST $SEC 1
J 0
(-7150 5600);
DISPLAY 0.680851 (-7150 5600);
PAINT MONO (-7150 5600);
DISPLAY INVISIBLE (-7150 5600);
FORCEPROP 0 LAST CDS_SEC 1
J 0
(-7150 5600);
DISPLAY 0.680851 (-7150 5600);
DISPLAY INVISIBLE (-7150 5600);
FORCEPROP 1 LASTPIN (-7200 5550) $PN 1
J 0
(-7190 5530);
DISPLAY 0.489362 (-7190 5530);
PAINT MONO (-7190 5530);
FORCEPROP 1 LASTPIN (-7200 5350) $PN 2
J 0
(-7190 5330);
DISPLAY 0.489362 (-7190 5330);
PAINT MONO (-7190 5330);
FORCEPROP 1 LAST PACK_TYPE 0402
J 0
(-7125 5275);
DISPLAY 0.489362 (-7125 5275);
PAINT SKYBLUE (-7125 5275);
FORCEPROP 1 LAST VOLTAGE 25V
J 0
(-7125 5475);
DISPLAY 0.489362 (-7125 5475);
PAINT SKYBLUE (-7125 5475);
FORCEPROP 1 LAST PART_NUMBER CH4104K1B00
J 0
(-7125 5325);
DISPLAY 0.489362 (-7125 5325);
PAINT SKYBLUE (-7125 5325);
FORCEPROP 1 LAST VALUE 0.1UF
J 0
(-7125 5525);
DISPLAY 0.489362 (-7125 5525);
PAINT SKYBLUE (-7125 5525);
FORCEPROP 1 LAST TOLERANCE 10%
J 0
(-7125 5425);
DISPLAY 0.489362 (-7125 5425);
PAINT SKYBLUE (-7125 5425);
FORCEPROP 1 LAST MATERIAL X7R
J 0
(-7125 5375);
DISPLAY 0.489362 (-7125 5375);
PAINT SKYBLUE (-7125 5375);
FORCEPROP 1 LAST PATH I24
J 0
(-7150 5600);
DISPLAY 0.978723 (-7150 5600);
PAINT WHITE (-7150 5600);
DISPLAY INVISIBLE (-7150 5600);
FORCEPROP 2 LAST BOM_COST OCP3.0 
J 0
(-7175 5575);
DISPLAY 0.680851 (-7175 5575);
DISPLAY INVISIBLE (-7175 5575);
FORCEPROP 2 LAST CDS_LIB pure_quanta
J 0
(-7200 5450);
DISPLAY INVISIBLE (-7200 5450);
FORCEADD UNIVERSAL_GND..1
(-7200 5250);
FORCEPROP 3 LASTPIN (-7200 5300) SIG_NAME GND\g
J 0
(-7190 5310);
DISPLAY 0.659574 (-7190 5310);
PAINT MONO (-7190 5310);
DISPLAY INVISIBLE (-7190 5310);
FORCEPROP 1 LAST HDL_POWER GND
J 1
(-7175 5175);
DISPLAY 0.872340 (-7175 5175);
PAINT GREEN (-7175 5175);
DISPLAY INVISIBLE (-7175 5175);
FORCEPROP 1 LAST PATH I25
J 0
(-7125 5250);
DISPLAY 0.872340 (-7125 5250);
PAINT AQUA (-7125 5250);
DISPLAY INVISIBLE (-7125 5250);
FORCEPROP 2 LAST CDS_LIB pure_quanta_power
J 0
(-7200 5250);
DISPLAY INVISIBLE (-7200 5250);
FORCEPROP 2 LAST BOM_COST OCP3.0 
J 0
(-7400 5325);
DISPLAY 0.680851 (-7400 5325);
DISPLAY INVISIBLE (-7400 5325);
FORCEADD SN74LVC1G07DBVR..1
(-6600 5125);
FORCEPROP 1 LAST LOCATION U82
J 0
(-6725 5380);
DISPLAY 0.489362 (-6725 5380);
PAINT SKYBLUE (-6725 5380);
FORCEPROP 0 LAST $SEC 1
J 0
(-6725 5525);
DISPLAY 0.680851 (-6725 5525);
PAINT MONO (-6725 5525);
DISPLAY INVISIBLE (-6725 5525);
FORCEPROP 0 LAST CDS_SEC 1
J 0
(-6725 5525);
DISPLAY 0.680851 (-6725 5525);
DISPLAY INVISIBLE (-6725 5525);
FORCEPROP 0 LASTPIN (-6775 5125) $PN 2
J 2
(-6785 5135);
DISPLAY 0.489362 (-6785 5135);
PAINT MONO (-6785 5135);
FORCEPROP 0 LASTPIN (-6775 5025) $PN 3
J 2
(-6785 5035);
DISPLAY 0.489362 (-6785 5035);
PAINT MONO (-6785 5035);
FORCEPROP 0 LASTPIN (-6425 5025) $PN 1
J 0
(-6415 5035);
DISPLAY 0.489362 (-6415 5035);
PAINT MONO (-6415 5035);
FORCEPROP 0 LASTPIN (-6775 5225) $PN 5
J 2
(-6785 5235);
DISPLAY 0.489362 (-6785 5235);
PAINT MONO (-6785 5235);
FORCEPROP 0 LASTPIN (-6425 5125) $PN 4
J 0
(-6415 5135);
DISPLAY 0.489362 (-6415 5135);
PAINT MONO (-6415 5135);
FORCEPROP 2 LAST PACK_TYPE SMLF
J 0
(-6725 5425);
DISPLAY 0.489362 (-6725 5425);
PAINT SKYBLUE (-6725 5425);
FORCEPROP 1 LAST PART_NUMBER AL1G0007024
J 0
(-6725 5335);
DISPLAY 0.489362 (-6725 5335);
PAINT SKYBLUE (-6725 5335);
FORCEPROP 2 LAST VALUE SN74LVC1G07DBVR
J 0
(-6725 5475);
DISPLAY 0.489362 (-6725 5475);
PAINT SKYBLUE (-6725 5475);
FORCEPROP 1 LAST MATERIAL IC
J 0
(-6725 5285);
DISPLAY 0.489362 (-6725 5285);
PAINT SKYBLUE (-6725 5285);
FORCEPROP 1 LAST PATH I26
J 0
(-6500 5280);
DISPLAY 0.723404 (-6500 5280);
PAINT GREEN (-6500 5280);
DISPLAY INVISIBLE (-6500 5280);
FORCEPROP 1 LAST NEEDS_NO_SIZE TRUE
J 0
(-6600 5125);
DISPLAY 0.468085 (-6600 5125);
PAINT GREEN (-6600 5125);
DISPLAY INVISIBLE (-6600 5125);
FORCEPROP 2 LAST CDS_LIB pure_quanta
J 0
(-6600 5125);
DISPLAY INVISIBLE (-6600 5125);
FORCEADD UNIVERSAL_GND..1
(-6850 4850);
FORCEPROP 3 LASTPIN (-6850 4900) SIG_NAME GND\g
J 0
(-6840 4910);
DISPLAY 0.659574 (-6840 4910);
PAINT MONO (-6840 4910);
DISPLAY INVISIBLE (-6840 4910);
FORCEPROP 1 LAST HDL_POWER GND
J 1
(-6825 4775);
DISPLAY 0.872340 (-6825 4775);
PAINT GREEN (-6825 4775);
DISPLAY INVISIBLE (-6825 4775);
FORCEPROP 1 LAST PATH I27
J 0
(-6775 4850);
DISPLAY 0.872340 (-6775 4850);
PAINT AQUA (-6775 4850);
DISPLAY INVISIBLE (-6775 4850);
FORCEPROP 2 LAST CDS_LIB pure_quanta_power
J 0
(-6850 4850);
DISPLAY INVISIBLE (-6850 4850);
FORCEPROP 2 LAST BOM_COST OCP3.0 
J 0
(-7050 4925);
DISPLAY 0.680851 (-7050 4925);
DISPLAY INVISIBLE (-7050 4925);
FORCEADD P1V0..1
(-7350 4125);
FORCEPROP 3 LASTPIN (-7350 4075) SIG_NAME P1V8_STBY\g
J 0
(-7340 4085);
DISPLAY 0.659574 (-7340 4085);
PAINT MONO (-7340 4085);
DISPLAY INVISIBLE (-7340 4085);
FORCEPROP 1 LAST HDL_POWER P1V8_STBY
J 1
(-7350 4175);
DISPLAY 0.489362 (-7350 4175);
PAINT GREEN (-7350 4175);
FORCEPROP 1 LAST PATH I28
J 0
(-7300 4150);
DISPLAY 0.872340 (-7300 4150);
PAINT AQUA (-7300 4150);
DISPLAY INVISIBLE (-7300 4150);
FORCEPROP 2 LAST CDS_LIB pure_quanta_power
J 0
(-7350 4125);
DISPLAY INVISIBLE (-7350 4125);
FORCEADD Q_CAP..1
(-7350 3825);
FORCEPROP 1 LAST LOCATION C219
J 0
(-7300 3925);
DISPLAY 0.489362 (-7300 3925);
PAINT SKYBLUE (-7300 3925);
FORCEPROP 0 LAST $SEC 1
J 0
(-7300 3975);
DISPLAY 0.680851 (-7300 3975);
PAINT MONO (-7300 3975);
DISPLAY INVISIBLE (-7300 3975);
FORCEPROP 0 LAST CDS_SEC 1
J 0
(-7300 3975);
DISPLAY 0.680851 (-7300 3975);
DISPLAY INVISIBLE (-7300 3975);
FORCEPROP 1 LASTPIN (-7350 3925) $PN 1
J 0
(-7340 3905);
DISPLAY 0.489362 (-7340 3905);
PAINT MONO (-7340 3905);
FORCEPROP 1 LASTPIN (-7350 3725) $PN 2
J 0
(-7340 3705);
DISPLAY 0.489362 (-7340 3705);
PAINT MONO (-7340 3705);
FORCEPROP 1 LAST VALUE 0.1UF
J 0
(-7275 3900);
DISPLAY 0.489362 (-7275 3900);
PAINT SKYBLUE (-7275 3900);
FORCEPROP 1 LAST VOLTAGE 25V
J 0
(-7275 3850);
DISPLAY 0.489362 (-7275 3850);
PAINT SKYBLUE (-7275 3850);
FORCEPROP 1 LAST TOLERANCE 10%
J 0
(-7275 3800);
DISPLAY 0.489362 (-7275 3800);
PAINT SKYBLUE (-7275 3800);
FORCEPROP 1 LAST PACK_TYPE 0402
J 0
(-7275 3650);
DISPLAY 0.489362 (-7275 3650);
PAINT SKYBLUE (-7275 3650);
FORCEPROP 1 LAST PART_NUMBER CH4104K1B00
J 0
(-7275 3700);
DISPLAY 0.489362 (-7275 3700);
PAINT SKYBLUE (-7275 3700);
FORCEPROP 1 LAST MATERIAL X7R
J 0
(-7275 3750);
DISPLAY 0.489362 (-7275 3750);
PAINT SKYBLUE (-7275 3750);
FORCEPROP 1 LAST PATH I29
J 0
(-7300 3975);
DISPLAY 0.978723 (-7300 3975);
PAINT WHITE (-7300 3975);
DISPLAY INVISIBLE (-7300 3975);
FORCEPROP 2 LAST BOM_COST OCP3.0 
J 0
(-7325 3950);
DISPLAY 0.680851 (-7325 3950);
DISPLAY INVISIBLE (-7325 3950);
FORCEPROP 2 LAST CDS_LIB pure_quanta
J 0
(-7350 3825);
DISPLAY INVISIBLE (-7350 3825);
FORCEADD Q_RES..1
(-2250 3450);
FORCEPROP 1 LAST LOCATION R950
J 0
(-2300 3500);
DISPLAY 0.489362 (-2300 3500);
PAINT SKYBLUE (-2300 3500);
FORCEPROP 0 LAST $SEC 1
J 0
(-2300 3550);
DISPLAY 0.680851 (-2300 3550);
PAINT MONO (-2300 3550);
DISPLAY INVISIBLE (-2300 3550);
FORCEPROP 0 LAST CDS_SEC 1
J 0
(-2300 3550);
DISPLAY 0.680851 (-2300 3550);
DISPLAY INVISIBLE (-2300 3550);
FORCEPROP 1 LASTPIN (-2350 3450) $PN 1
J 0
(-2338 3462);
DISPLAY 0.489362 (-2338 3462);
PAINT MONO (-2338 3462);
FORCEPROP 1 LASTPIN (-2150 3450) $PN 2
J 0
(-2188 3462);
DISPLAY 0.489362 (-2188 3462);
PAINT MONO (-2188 3462);
FORCEPROP 1 LAST PACK_TYPE 0402LF
J 0
(-2025 3375);
DISPLAY 0.489362 (-2025 3375);
PAINT SKYBLUE (-2025 3375);
FORCEPROP 1 LAST VALUE 200
J 2
(-2400 3375);
DISPLAY 0.489362 (-2400 3375);
PAINT SKYBLUE (-2400 3375);
FORCEPROP 1 LAST TOLERANCE 1%
J 0
(-2375 3375);
DISPLAY 0.489362 (-2375 3375);
PAINT SKYBLUE (-2375 3375);
FORCEPROP 1 LAST MATERIAL CHIP
J 0
(-2150 3375);
DISPLAY 0.489362 (-2150 3375);
PAINT SKYBLUE (-2150 3375);
FORCEPROP 1 LAST WATTAGE 1/16W
J 2
(-2175 3375);
DISPLAY 0.489362 (-2175 3375);
PAINT SKYBLUE (-2175 3375);
FORCEPROP 1 LAST PART_NUMBER CS12002FB06
J 0
(-2225 3500);
DISPLAY 0.638298 (-2225 3500);
PAINT SKYBLUE (-2225 3500);
DISPLAY INVISIBLE (-2225 3500);
FORCEPROP 1 LAST PATH I3
J 0
(-2300 3600);
DISPLAY 0.978723 (-2300 3600);
PAINT WHITE (-2300 3600);
DISPLAY INVISIBLE (-2300 3600);
FORCEPROP 2 LAST CDS_LIB pure_quanta
J 0
(-2250 3450);
DISPLAY INVISIBLE (-2250 3450);
FORCEADD UNIVERSAL_GND..1
(-7350 3625);
FORCEPROP 3 LASTPIN (-7350 3675) SIG_NAME GND\g
J 0
(-7340 3685);
DISPLAY 0.659574 (-7340 3685);
PAINT MONO (-7340 3685);
DISPLAY INVISIBLE (-7340 3685);
FORCEPROP 1 LAST HDL_POWER GND
J 1
(-7325 3550);
DISPLAY 0.872340 (-7325 3550);
PAINT GREEN (-7325 3550);
DISPLAY INVISIBLE (-7325 3550);
FORCEPROP 1 LAST PATH I30
J 0
(-7275 3625);
DISPLAY 0.872340 (-7275 3625);
PAINT AQUA (-7275 3625);
DISPLAY INVISIBLE (-7275 3625);
FORCEPROP 2 LAST CDS_LIB pure_quanta_power
J 0
(-7350 3625);
DISPLAY INVISIBLE (-7350 3625);
FORCEPROP 2 LAST BOM_COST OCP3.0 
J 0
(-7550 3700);
DISPLAY 0.680851 (-7550 3700);
DISPLAY INVISIBLE (-7550 3700);
FORCEADD SN74LVC1G07DBVR..1
(-6750 3500);
FORCEPROP 1 LAST LOCATION U86
J 0
(-6875 3755);
DISPLAY 0.489362 (-6875 3755);
PAINT SKYBLUE (-6875 3755);
FORCEPROP 0 LAST $SEC 1
J 0
(-6875 3900);
DISPLAY 0.680851 (-6875 3900);
PAINT MONO (-6875 3900);
DISPLAY INVISIBLE (-6875 3900);
FORCEPROP 0 LAST CDS_SEC 1
J 0
(-6875 3900);
DISPLAY 0.680851 (-6875 3900);
DISPLAY INVISIBLE (-6875 3900);
FORCEPROP 0 LASTPIN (-6925 3500) $PN 2
J 2
(-6935 3510);
DISPLAY 0.489362 (-6935 3510);
PAINT MONO (-6935 3510);
FORCEPROP 0 LASTPIN (-6925 3400) $PN 3
J 2
(-6935 3410);
DISPLAY 0.489362 (-6935 3410);
PAINT MONO (-6935 3410);
FORCEPROP 0 LASTPIN (-6575 3400) $PN 1
J 0
(-6565 3410);
DISPLAY 0.489362 (-6565 3410);
PAINT MONO (-6565 3410);
FORCEPROP 0 LASTPIN (-6925 3600) $PN 5
J 2
(-6935 3610);
DISPLAY 0.489362 (-6935 3610);
PAINT MONO (-6935 3610);
FORCEPROP 0 LASTPIN (-6575 3500) $PN 4
J 0
(-6565 3510);
DISPLAY 0.489362 (-6565 3510);
PAINT MONO (-6565 3510);
FORCEPROP 2 LAST PACK_TYPE SMLF
J 0
(-6875 3800);
DISPLAY 0.489362 (-6875 3800);
PAINT SKYBLUE (-6875 3800);
FORCEPROP 1 LAST PART_NUMBER AL1G0007024
J 0
(-6875 3710);
DISPLAY 0.489362 (-6875 3710);
PAINT SKYBLUE (-6875 3710);
FORCEPROP 2 LAST VALUE SN74LVC1G07DBVR
J 0
(-6875 3850);
DISPLAY 0.489362 (-6875 3850);
PAINT SKYBLUE (-6875 3850);
FORCEPROP 1 LAST MATERIAL IC
J 0
(-6875 3660);
DISPLAY 0.489362 (-6875 3660);
PAINT SKYBLUE (-6875 3660);
FORCEPROP 1 LAST PATH I31
J 0
(-6650 3655);
DISPLAY 0.723404 (-6650 3655);
PAINT GREEN (-6650 3655);
DISPLAY INVISIBLE (-6650 3655);
FORCEPROP 1 LAST NEEDS_NO_SIZE TRUE
J 0
(-6750 3500);
DISPLAY 0.468085 (-6750 3500);
PAINT GREEN (-6750 3500);
DISPLAY INVISIBLE (-6750 3500);
FORCEPROP 2 LAST CDS_LIB pure_quanta
J 0
(-6750 3500);
DISPLAY INVISIBLE (-6750 3500);
FORCEADD UNIVERSAL_GND..1
(-7000 3225);
FORCEPROP 3 LASTPIN (-7000 3275) SIG_NAME GND\g
J 0
(-6990 3285);
DISPLAY 0.659574 (-6990 3285);
PAINT MONO (-6990 3285);
DISPLAY INVISIBLE (-6990 3285);
FORCEPROP 2 LAST BOM_COST OCP3.0 
J 0
(-7200 3300);
DISPLAY 0.680851 (-7200 3300);
DISPLAY INVISIBLE (-7200 3300);
FORCEPROP 1 LAST HDL_POWER GND
J 1
(-6975 3150);
DISPLAY 0.872340 (-6975 3150);
PAINT GREEN (-6975 3150);
DISPLAY INVISIBLE (-6975 3150);
FORCEPROP 1 LAST PATH I32
J 0
(-6925 3225);
DISPLAY 0.872340 (-6925 3225);
PAINT AQUA (-6925 3225);
DISPLAY INVISIBLE (-6925 3225);
FORCEPROP 2 LAST CDS_LIB pure_quanta_power
J 0
(-7000 3225);
DISPLAY INVISIBLE (-7000 3225);
FORCEADD Q_RES..1
(-7950 5125);
FORCEPROP 1 LAST LOCATION R934
J 0
(-8000 5175);
DISPLAY 0.489362 (-8000 5175);
PAINT SKYBLUE (-8000 5175);
FORCEPROP 0 LAST $SEC 1
J 0
(-8000 5225);
DISPLAY 0.680851 (-8000 5225);
PAINT MONO (-8000 5225);
DISPLAY INVISIBLE (-8000 5225);
FORCEPROP 0 LAST CDS_SEC 1
J 0
(-8000 5225);
DISPLAY 0.680851 (-8000 5225);
DISPLAY INVISIBLE (-8000 5225);
FORCEPROP 1 LASTPIN (-8050 5125) $PN 1
J 0
(-8038 5137);
DISPLAY 0.489362 (-8038 5137);
PAINT MONO (-8038 5137);
FORCEPROP 1 LASTPIN (-7850 5125) $PN 2
J 0
(-7888 5137);
DISPLAY 0.489362 (-7888 5137);
PAINT MONO (-7888 5137);
FORCEPROP 1 LAST VALUE 0
J 2
(-8075 5125);
DISPLAY 0.489362 (-8075 5125);
PAINT SKYBLUE (-8075 5125);
FORCEPROP 2 LAST ROOM RST_CPU0_PLD_TO_DIMM
J 2
(-7925 5225);
DISPLAY 0.744681 (-7925 5225);
PAINT RED (-7925 5225);
DISPLAY INVISIBLE (-7925 5225);
FORCEPROP 1 LAST PACK_TYPE 0402LF
J 2
(-7775 5050);
DISPLAY 0.489362 (-7775 5050);
PAINT SKYBLUE (-7775 5050);
DISPLAY INVISIBLE (-7775 5050);
FORCEPROP 1 LAST PART_NUMBER CS00002JB38
J 2
(-7850 5175);
DISPLAY 0.489362 (-7850 5175);
PAINT SKYBLUE (-7850 5175);
DISPLAY INVISIBLE (-7850 5175);
FORCEPROP 1 LAST TOLERANCE 5%
J 0
(-8075 5100);
DISPLAY 0.489362 (-8075 5100);
PAINT SKYBLUE (-8075 5100);
DISPLAY INVISIBLE (-8075 5100);
FORCEPROP 1 LAST MATERIAL CHIP
J 2
(-7775 5100);
DISPLAY 0.489362 (-7775 5100);
PAINT SKYBLUE (-7775 5100);
DISPLAY INVISIBLE (-7775 5100);
FORCEPROP 1 LAST WATTAGE 1/16W
J 2
(-8025 5050);
DISPLAY 0.489362 (-8025 5050);
PAINT SKYBLUE (-8025 5050);
DISPLAY INVISIBLE (-8025 5050);
FORCEPROP 1 LAST PATH I33
J 0
(-8000 5275);
DISPLAY 0.978723 (-8000 5275);
PAINT WHITE (-8000 5275);
DISPLAY INVISIBLE (-8000 5275);
FORCEPROP 2 LAST CDS_LIB pure_quanta
J 0
(-7950 5125);
DISPLAY INVISIBLE (-7950 5125);
FORCEPROP 2 LAST BOM_COST MEM
J 2
(-7925 5275);
DISPLAY 0.744681 (-7925 5275);
PAINT WHITE (-7925 5275);
DISPLAY INVISIBLE (-7925 5275);
FORCEADD Q_RES..1
(-7950 4875);
FORCEPROP 1 LAST LOCATION R941
J 0
(-8125 4900);
DISPLAY 0.489362 (-8125 4900);
PAINT SKYBLUE (-8125 4900);
FORCEPROP 0 LAST $SEC 1
J 0
(-8125 4950);
DISPLAY 0.680851 (-8125 4950);
PAINT MONO (-8125 4950);
DISPLAY INVISIBLE (-8125 4950);
FORCEPROP 0 LAST CDS_SEC 1
J 0
(-8125 4950);
DISPLAY 0.680851 (-8125 4950);
DISPLAY INVISIBLE (-8125 4950);
FORCEPROP 1 LASTPIN (-8050 4875) $PN 1
J 0
(-8038 4887);
DISPLAY 0.489362 (-8038 4887);
PAINT MONO (-8038 4887);
FORCEPROP 1 LASTPIN (-7850 4875) $PN 2
J 0
(-7888 4887);
DISPLAY 0.489362 (-7888 4887);
PAINT MONO (-7888 4887);
FORCEPROP 1 LAST VALUE 0
J 2
(-7750 4875);
DISPLAY 0.489362 (-7750 4875);
PAINT SKYBLUE (-7750 4875);
FORCEPROP 1 LAST MATERIAL EMPTY
J 0
(-7750 4900);
DISPLAY 0.489362 (-7750 4900);
PAINT RED (-7750 4900);
FORCEPROP 1 LAST PACK_TYPE 0402LF
J 0
(-7700 4725);
DISPLAY 0.978723 (-7700 4725);
PAINT SKYBLUE (-7700 4725);
DISPLAY INVISIBLE (-7700 4725);
FORCEPROP 1 LAST PART_NUMBER CS00002JB38
J 0
(-8000 5000);
DISPLAY 0.978723 (-8000 5000);
PAINT SKYBLUE (-8000 5000);
DISPLAY INVISIBLE (-8000 5000);
FORCEPROP 1 LAST TOLERANCE 5%
J 0
(-7950 4775);
DISPLAY 0.978723 (-7950 4775);
PAINT SKYBLUE (-7950 4775);
DISPLAY INVISIBLE (-7950 4775);
FORCEPROP 1 LAST WATTAGE 1/16W
J 2
(-7975 4725);
DISPLAY 0.978723 (-7975 4725);
PAINT SKYBLUE (-7975 4725);
DISPLAY INVISIBLE (-7975 4725);
FORCEPROP 1 LAST PATH I34
J 0
(-8000 5025);
DISPLAY 0.978723 (-8000 5025);
PAINT WHITE (-8000 5025);
DISPLAY INVISIBLE (-8000 5025);
FORCEPROP 2 LAST CDS_LIB pure_quanta
J 0
(-7950 4875);
DISPLAY INVISIBLE (-7950 4875);
FORCEADD OFFPAGE..1
(-8550 3500);
FORCEPROP 2 LAST $XR0 80 
J 0
(-8771 3500);
DISPLAY 0.638298 (-8771 3500);
PAINT MONO (-8771 3500);
FORCEPROP 1 LAST COMMENT_BODY TRUE
J 0
(-8425 3400);
DISPLAY 0.872340 (-8425 3400);
PAINT GREEN (-8425 3400);
DISPLAY INVISIBLE (-8425 3400);
FORCEPROP 1 LAST OFFPAGE TRUE
J 0
(-8225 3375);
DISPLAY 0.872340 (-8225 3375);
PAINT GREEN (-8225 3375);
DISPLAY INVISIBLE (-8225 3375);
FORCEPROP 2 LAST PATH I35
J 0
(-8750 3550);
DISPLAY 0.680851 (-8750 3550);
DISPLAY INVISIBLE (-8750 3550);
FORCEPROP 2 LAST CDS_LIB standard
J 0
(-8550 3500);
DISPLAY INVISIBLE (-8550 3500);
FORCEADD OFFPAGE..1
(-8700 4875);
FORCEPROP 2 LAST $XR0 28 
J 0
(-8921 4875);
DISPLAY 0.638298 (-8921 4875);
PAINT MONO (-8921 4875);
FORCEPROP 2 LAST CDS_LIB standard
J 0
(-8700 4875);
DISPLAY INVISIBLE (-8700 4875);
FORCEPROP 1 LAST OFFPAGE TRUE
J 0
(-8375 4750);
DISPLAY 0.872340 (-8375 4750);
PAINT GREEN (-8375 4750);
DISPLAY INVISIBLE (-8375 4750);
FORCEPROP 1 LAST COMMENT_BODY TRUE
J 0
(-8575 4775);
DISPLAY 0.872340 (-8575 4775);
PAINT GREEN (-8575 4775);
DISPLAY INVISIBLE (-8575 4775);
FORCEPROP 2 LAST PATH I36
J 0
(-8950 4925);
DISPLAY 0.680851 (-8950 4925);
DISPLAY INVISIBLE (-8950 4925);
FORCEADD OFFPAGE..1
(-9025 5125);
FORCEPROP 2 LAST $XR1 34 
J 0
(-9336 5125);
DISPLAY 0.638298 (-9336 5125);
PAINT MONO (-9336 5125);
FORCEPROP 2 LAST $XR0 28 
J 0
(-9246 5125);
DISPLAY 0.638298 (-9246 5125);
PAINT MONO (-9246 5125);
FORCEPROP 2 LAST CDS_LIB standard
J 0
(-9025 5125);
DISPLAY INVISIBLE (-9025 5125);
FORCEPROP 1 LAST OFFPAGE TRUE
J 0
(-8700 5000);
DISPLAY 0.872340 (-8700 5000);
PAINT GREEN (-8700 5000);
DISPLAY INVISIBLE (-8700 5000);
FORCEPROP 1 LAST COMMENT_BODY TRUE
J 0
(-8900 5025);
DISPLAY 0.872340 (-8900 5025);
PAINT GREEN (-8900 5025);
DISPLAY INVISIBLE (-8900 5025);
FORCEPROP 2 LAST PATH I37
J 0
(-9225 5175);
DISPLAY 0.680851 (-9225 5175);
DISPLAY INVISIBLE (-9225 5175);
FORCEADD Q_LED..1
R 2
(-4275 550);
FORCEPROP 1 LAST LOCATION D49
J 2
(-4175 735);
DISPLAY 0.489362 (-4175 735);
PAINT SKYBLUE (-4175 735);
FORCEPROP 0 LAST $SEC 1
J 0
(-4175 925);
DISPLAY 0.680851 (-4175 925);
PAINT MONO (-4175 925);
DISPLAY INVISIBLE (-4175 925);
FORCEPROP 0 LAST CDS_SEC 1
J 0
(-4175 925);
DISPLAY 0.680851 (-4175 925);
DISPLAY INVISIBLE (-4175 925);
FORCEPROP 0 LASTPIN (-4125 550) $PN A
J 0
(-4115 560);
DISPLAY 0.489362 (-4115 560);
PAINT MONO (-4115 560);
FORCEPROP 0 LASTPIN (-4425 550) $PN C
J 2
(-4435 560);
DISPLAY 0.489362 (-4435 560);
PAINT MONO (-4435 560);
FORCEPROP 2 LAST PACK_TYPE SMLF
J 2
(-4175 775);
DISPLAY 0.489362 (-4175 775);
PAINT SKYBLUE (-4175 775);
FORCEPROP 2 LAST COLOR LED_GREEN
J 2
(-4175 875);
DISPLAY 0.489362 (-4175 875);
FORCEPROP 1 LAST PART_NUMBER BEGR0278Z00
J 2
(-4175 685);
DISPLAY 0.489362 (-4175 685);
PAINT SKYBLUE (-4175 685);
FORCEPROP 1 LAST MATERIAL IC
J 2
(-4175 630);
DISPLAY 0.489362 (-4175 630);
PAINT SKYBLUE (-4175 630);
FORCEPROP 2 LAST MANUF_PN 19-213/GVC-AMNB/3T
J 2
(-4175 825);
DISPLAY 0.680851 (-4175 825);
FORCEPROP 1 LAST PATH I38
J 2
(-4400 630);
DISPLAY 0.723404 (-4400 630);
PAINT GREEN (-4400 630);
DISPLAY INVISIBLE (-4400 630);
FORCEPROP 2 LAST CDS_LIB pure_quanta
J 2
(-4275 550);
DISPLAY INVISIBLE (-4275 550);
FORCEPROP 1 LAST NEEDS_NO_SIZE TRUE
J 2
(-4275 550);
DISPLAY 0.468085 (-4275 550);
PAINT GREEN (-4275 550);
DISPLAY INVISIBLE (-4275 550);
FORCEADD UNIVERSAL_GND..1
(-4750 375);
FORCEPROP 3 LASTPIN (-4750 425) SIG_NAME GND\g
J 0
(-4740 435);
DISPLAY 0.659574 (-4740 435);
PAINT MONO (-4740 435);
DISPLAY INVISIBLE (-4740 435);
FORCEPROP 1 LAST HDL_POWER GND
J 1
(-4725 300);
DISPLAY 0.872340 (-4725 300);
PAINT GREEN (-4725 300);
DISPLAY INVISIBLE (-4725 300);
FORCEPROP 1 LAST PATH I39
J 0
(-4675 375);
DISPLAY 0.872340 (-4675 375);
PAINT AQUA (-4675 375);
DISPLAY INVISIBLE (-4675 375);
FORCEPROP 2 LAST BOM_COST OCP3.0 
J 0
(-4950 450);
DISPLAY 0.680851 (-4950 450);
DISPLAY INVISIBLE (-4950 450);
FORCEPROP 2 LAST CDS_LIB pure_quanta_power
J 0
(-4750 375);
DISPLAY INVISIBLE (-4750 375);
FORCEADD UNIVERSAL_POWER..1
(-3950 5775);
FORCEPROP 3 LASTPIN (-3950 5725) SIG_NAME P3V3_STBY\g
J 0
(-3940 5735);
DISPLAY 0.659574 (-3940 5735);
PAINT MONO (-3940 5735);
DISPLAY INVISIBLE (-3940 5735);
FORCEPROP 1 LAST HDL_POWER P3V3_STBY
J 1
(-3950 5825);
DISPLAY 0.489362 (-3950 5825);
PAINT GREEN (-3950 5825);
FORCEPROP 1 LAST PATH I4
J 0
(-3900 5800);
DISPLAY 0.872340 (-3900 5800);
PAINT AQUA (-3900 5800);
DISPLAY INVISIBLE (-3900 5800);
FORCEPROP 2 LAST CDS_LIB pure_quanta_power
J 0
(-3950 5775);
DISPLAY INVISIBLE (-3950 5775);
FORCEPROP 2 LAST BOM_COST OCP3.0 
J 0
(-3950 5875);
DISPLAY 0.680851 (-3950 5875);
DISPLAY INVISIBLE (-3950 5875);
FORCEADD P1V0..1
(-2725 975);
FORCEPROP 3 LASTPIN (-2725 925) SIG_NAME P5V_STBY\g
J 0
(-2715 935);
DISPLAY 0.659574 (-2715 935);
PAINT MONO (-2715 935);
DISPLAY INVISIBLE (-2715 935);
FORCEPROP 1 LAST HDL_POWER P5V_STBY
J 1
(-2725 1025);
DISPLAY 0.489362 (-2725 1025);
PAINT GREEN (-2725 1025);
FORCEPROP 1 LAST PATH I40
J 0
(-2675 1000);
DISPLAY 0.872340 (-2675 1000);
PAINT AQUA (-2675 1000);
DISPLAY INVISIBLE (-2675 1000);
FORCEPROP 2 LAST CDS_LIB pure_quanta_power
J 0
(-2725 975);
DISPLAY INVISIBLE (-2725 975);
FORCEADD Q_RES..1
(-3275 550);
FORCEPROP 1 LAST LOCATION R1207
J 0
(-3325 600);
DISPLAY 0.489362 (-3325 600);
PAINT SKYBLUE (-3325 600);
FORCEPROP 0 LAST $SEC 1
J 0
(-3325 700);
DISPLAY 0.680851 (-3325 700);
PAINT MONO (-3325 700);
DISPLAY INVISIBLE (-3325 700);
FORCEPROP 0 LAST CDS_SEC 1
J 0
(-3325 700);
DISPLAY 0.680851 (-3325 700);
DISPLAY INVISIBLE (-3325 700);
FORCEPROP 1 LASTPIN (-3375 550) $PN 1
J 0
(-3363 562);
DISPLAY 0.489362 (-3363 562);
PAINT MONO (-3363 562);
FORCEPROP 1 LASTPIN (-3175 550) $PN 2
J 0
(-3213 562);
DISPLAY 0.489362 (-3213 562);
PAINT MONO (-3213 562);
FORCEPROP 1 LAST PACK_TYPE 0603LF
J 0
(-3025 400);
DISPLAY 0.489362 (-3025 400);
PAINT SKYBLUE (-3025 400);
FORCEPROP 1 LAST PART_NUMBER CS13303F917
J 0
(-3325 650);
DISPLAY 0.489362 (-3325 650);
PAINT SKYBLUE (-3325 650);
FORCEPROP 1 LAST VALUE 330
J 2
(-3300 450);
DISPLAY 0.489362 (-3300 450);
PAINT SKYBLUE (-3300 450);
FORCEPROP 1 LAST TOLERANCE 1%
J 0
(-3275 450);
DISPLAY 0.489362 (-3275 450);
PAINT SKYBLUE (-3275 450);
FORCEPROP 1 LAST MATERIAL CHIP
J 0
(-3275 400);
DISPLAY 0.489362 (-3275 400);
PAINT SKYBLUE (-3275 400);
FORCEPROP 1 LAST WATTAGE 1/10W
J 2
(-3300 400);
DISPLAY 0.489362 (-3300 400);
PAINT SKYBLUE (-3300 400);
FORCEPROP 1 LAST PATH I41
J 0
(-3325 700);
DISPLAY 0.978723 (-3325 700);
PAINT WHITE (-3325 700);
DISPLAY INVISIBLE (-3325 700);
FORCEPROP 2 LAST CDS_LIB pure_quanta
J 0
(-3275 550);
DISPLAY INVISIBLE (-3275 550);
FORCEADD Q_RES..1
(-3125 1975);
FORCEPROP 1 LAST LOCATION R1208
J 0
(-3175 2025);
DISPLAY 0.489362 (-3175 2025);
PAINT SKYBLUE (-3175 2025);
FORCEPROP 0 LAST $SEC 1
J 0
(-3175 2125);
DISPLAY 0.680851 (-3175 2125);
PAINT MONO (-3175 2125);
DISPLAY INVISIBLE (-3175 2125);
FORCEPROP 0 LAST CDS_SEC 1
J 0
(-3175 2125);
DISPLAY 0.680851 (-3175 2125);
DISPLAY INVISIBLE (-3175 2125);
FORCEPROP 1 LASTPIN (-3225 1975) $PN 1
J 0
(-3213 1987);
DISPLAY 0.489362 (-3213 1987);
PAINT MONO (-3213 1987);
FORCEPROP 1 LASTPIN (-3025 1975) $PN 2
J 0
(-3063 1987);
DISPLAY 0.489362 (-3063 1987);
PAINT MONO (-3063 1987);
FORCEPROP 1 LAST PACK_TYPE 0603LF
J 0
(-2875 1825);
DISPLAY 0.489362 (-2875 1825);
PAINT SKYBLUE (-2875 1825);
FORCEPROP 1 LAST PART_NUMBER CS13303F917
J 0
(-3175 2075);
DISPLAY 0.489362 (-3175 2075);
PAINT SKYBLUE (-3175 2075);
FORCEPROP 1 LAST VALUE 330
J 2
(-3150 1875);
DISPLAY 0.489362 (-3150 1875);
PAINT SKYBLUE (-3150 1875);
FORCEPROP 1 LAST TOLERANCE 1%
J 0
(-3125 1875);
DISPLAY 0.489362 (-3125 1875);
PAINT SKYBLUE (-3125 1875);
FORCEPROP 1 LAST MATERIAL CHIP
J 0
(-3125 1825);
DISPLAY 0.489362 (-3125 1825);
PAINT SKYBLUE (-3125 1825);
FORCEPROP 1 LAST WATTAGE 1/10W
J 2
(-3150 1825);
DISPLAY 0.489362 (-3150 1825);
PAINT SKYBLUE (-3150 1825);
FORCEPROP 1 LAST PATH I42
J 0
(-3175 2125);
DISPLAY 0.978723 (-3175 2125);
PAINT WHITE (-3175 2125);
DISPLAY INVISIBLE (-3175 2125);
FORCEPROP 2 LAST CDS_LIB pure_quanta
J 0
(-3125 1975);
DISPLAY INVISIBLE (-3125 1975);
FORCEADD Q_LED..1
R 2
(-4125 1975);
FORCEPROP 1 LAST LOCATION D46
J 2
(-4025 2160);
DISPLAY 0.489362 (-4025 2160);
PAINT SKYBLUE (-4025 2160);
FORCEPROP 0 LAST $SEC 1
J 0
(-4025 2350);
DISPLAY 0.680851 (-4025 2350);
PAINT MONO (-4025 2350);
DISPLAY INVISIBLE (-4025 2350);
FORCEPROP 0 LAST CDS_SEC 1
J 0
(-4025 2350);
DISPLAY 0.680851 (-4025 2350);
DISPLAY INVISIBLE (-4025 2350);
FORCEPROP 0 LASTPIN (-3975 1975) $PN A
J 0
(-3965 1985);
DISPLAY 0.489362 (-3965 1985);
PAINT MONO (-3965 1985);
FORCEPROP 0 LASTPIN (-4275 1975) $PN C
J 2
(-4285 1985);
DISPLAY 0.489362 (-4285 1985);
PAINT MONO (-4285 1985);
FORCEPROP 2 LAST PACK_TYPE SMLF
J 2
(-4025 2200);
DISPLAY 0.489362 (-4025 2200);
PAINT SKYBLUE (-4025 2200);
FORCEPROP 2 LAST COLOR LED_GREEN
J 2
(-4025 2300);
DISPLAY 0.489362 (-4025 2300);
FORCEPROP 1 LAST PART_NUMBER BEGR0278Z00
J 2
(-4025 2110);
DISPLAY 0.489362 (-4025 2110);
PAINT SKYBLUE (-4025 2110);
FORCEPROP 1 LAST MATERIAL IC
J 2
(-4025 2055);
DISPLAY 0.489362 (-4025 2055);
PAINT SKYBLUE (-4025 2055);
FORCEPROP 2 LASTPIN (-3975 1975) SIG_NAME PU_P12V_ALL_PWROK_LED
J 0
(-4010 2010);
DISPLAY 0.489362 (-4010 2010);
FORCEPROP 2 LASTPROP $XRERR UNIQUE?
J 0
(-4250 2010);
DISPLAY 0.638298 (-4250 2010);
PAINT MONO (-4250 2010);
DISPLAY INVISIBLE (-4250 2010);
FORCEPROP 2 LAST MANUF_PN 19-213/GVC-AMNB/3T
J 2
(-4025 2250);
DISPLAY 0.680851 (-4025 2250);
FORCEPROP 1 LAST PATH I43
J 2
(-4250 2055);
DISPLAY 0.723404 (-4250 2055);
PAINT GREEN (-4250 2055);
DISPLAY INVISIBLE (-4250 2055);
FORCEPROP 1 LAST NEEDS_NO_SIZE TRUE
J 2
(-4125 1975);
DISPLAY 0.468085 (-4125 1975);
PAINT GREEN (-4125 1975);
DISPLAY INVISIBLE (-4125 1975);
FORCEPROP 2 LAST CDS_LIB pure_quanta
J 0
(-4125 1975);
DISPLAY INVISIBLE (-4125 1975);
FORCEADD MOSFET_N_GSD..1
(-4875 1625);
FORCEPROP 1 LAST LOCATION Q12
J 0
(-4774 1670);
DISPLAY 0.489362 (-4774 1670);
PAINT SKYBLUE (-4774 1670);
FORCEPROP 0 LAST $SEC 1
J 0
(-4775 1850);
DISPLAY 0.680851 (-4775 1850);
PAINT MONO (-4775 1850);
DISPLAY INVISIBLE (-4775 1850);
FORCEPROP 0 LAST CDS_SEC 1
J 0
(-4775 1850);
DISPLAY 0.680851 (-4775 1850);
DISPLAY INVISIBLE (-4775 1850);
FORCEPROP 0 LASTPIN (-4850 1775) $PN D
R 1
J 0
(-4860 1785);
DISPLAY 0.489362 (-4860 1785);
PAINT MONO (-4860 1785);
FORCEPROP 0 LASTPIN (-5050 1575) $PN G
J 2
(-5060 1585);
DISPLAY 0.489362 (-5060 1585);
PAINT MONO (-5060 1585);
FORCEPROP 0 LASTPIN (-4850 1475) $PN S
R 1
J 2
(-4860 1465);
DISPLAY 0.489362 (-4860 1465);
PAINT MONO (-4860 1465);
FORCEPROP 1 LAST PART_NUMBER BAM01380023
J 0
(-4774 1605);
DISPLAY 0.489362 (-4774 1605);
PAINT SKYBLUE (-4774 1605);
FORCEPROP 2 LAST VALUE NX138BK
J 0
(-4775 1750);
DISPLAY 0.489362 (-4775 1750);
PAINT SKYBLUE (-4775 1750);
FORCEPROP 1 LAST MATERIAL IC
J 0
(-4774 1525);
DISPLAY 0.489362 (-4774 1525);
PAINT SKYBLUE (-4774 1525);
FORCEPROP 2 LAST PART_TYPE SMLF
J 0
(-4775 1800);
DISPLAY 1.021277 (-4775 1800);
FORCEPROP 1 LAST PATH I44
J 0
(-4875 1625);
DISPLAY 0.723404 (-4875 1625);
PAINT GREEN (-4875 1625);
DISPLAY INVISIBLE (-4875 1625);
FORCEPROP 1 LAST NEEDS_NO_SIZE TRUE
J 0
(-4875 1625);
DISPLAY 0.468085 (-4875 1625);
PAINT GREEN (-4875 1625);
DISPLAY INVISIBLE (-4875 1625);
FORCEPROP 1 LAST CDS_LMAN_SYM_OUTLINE -100,100,100,-100
J 0
(-4875 1625);
DISPLAY 0.468085 (-4875 1625);
PAINT GREEN (-4875 1625);
DISPLAY INVISIBLE (-4875 1625);
FORCEPROP 2 LAST CDS_LIB pure_quanta
J 0
(-4875 1625);
DISPLAY INVISIBLE (-4875 1625);
FORCEADD P1V0..1
(-2550 2400);
FORCEPROP 3 LASTPIN (-2550 2350) SIG_NAME P5V_STBY\g
J 0
(-2540 2360);
DISPLAY 0.659574 (-2540 2360);
PAINT MONO (-2540 2360);
DISPLAY INVISIBLE (-2540 2360);
FORCEPROP 1 LAST HDL_POWER P5V_STBY
J 1
(-2550 2450);
DISPLAY 0.489362 (-2550 2450);
PAINT GREEN (-2550 2450);
FORCEPROP 1 LAST PATH I45
J 0
(-2500 2425);
DISPLAY 0.872340 (-2500 2425);
PAINT AQUA (-2500 2425);
DISPLAY INVISIBLE (-2500 2425);
FORCEPROP 2 LAST CDS_LIB pure_quanta_power
J 0
(-2550 2400);
DISPLAY INVISIBLE (-2550 2400);
FORCEADD UNIVERSAL_GND..1
(-4850 1300);
FORCEPROP 3 LASTPIN (-4850 1350) SIG_NAME GND\g
J 0
(-4840 1360);
DISPLAY 0.659574 (-4840 1360);
PAINT MONO (-4840 1360);
DISPLAY INVISIBLE (-4840 1360);
FORCEPROP 1 LAST HDL_POWER GND
J 1
(-4825 1225);
DISPLAY 0.872340 (-4825 1225);
PAINT GREEN (-4825 1225);
DISPLAY INVISIBLE (-4825 1225);
FORCEPROP 1 LAST PATH I46
J 0
(-4775 1300);
DISPLAY 0.872340 (-4775 1300);
PAINT AQUA (-4775 1300);
DISPLAY INVISIBLE (-4775 1300);
FORCEPROP 2 LAST CDS_LIB pure_quanta_power
J 0
(-4850 1300);
DISPLAY INVISIBLE (-4850 1300);
FORCEPROP 2 LAST BOM_COST OCP3.0 
J 0
(-5050 1375);
DISPLAY 0.680851 (-5050 1375);
DISPLAY INVISIBLE (-5050 1375);
FORCEADD OFFPAGE..1
(-5875 1575);
FORCEPROP 2 LAST $XR0 80 
J 0
(-6096 1575);
DISPLAY 0.638298 (-6096 1575);
PAINT MONO (-6096 1575);
FORCEPROP 2 LAST CDS_LIB standard
J 0
(-5875 1575);
DISPLAY INVISIBLE (-5875 1575);
FORCEPROP 1 LAST OFFPAGE TRUE
J 0
(-5550 1450);
DISPLAY 0.872340 (-5550 1450);
PAINT GREEN (-5550 1450);
DISPLAY INVISIBLE (-5550 1450);
FORCEPROP 1 LAST COMMENT_BODY TRUE
J 0
(-5750 1475);
DISPLAY 0.872340 (-5750 1475);
PAINT GREEN (-5750 1475);
DISPLAY INVISIBLE (-5750 1475);
FORCEPROP 2 LAST PATH I47
J 0
(-5825 1650);
DISPLAY 0.680851 (-5825 1650);
DISPLAY INVISIBLE (-5825 1650);
FORCEADD P1V0..1
(-7200 5750);
FORCEPROP 3 LASTPIN (-7200 5700) SIG_NAME P1V8_STBY\g
J 0
(-7190 5710);
DISPLAY 0.659574 (-7190 5710);
PAINT MONO (-7190 5710);
DISPLAY INVISIBLE (-7190 5710);
FORCEPROP 1 LAST HDL_POWER P1V8_STBY
J 1
(-7200 5800);
DISPLAY 0.489362 (-7200 5800);
PAINT GREEN (-7200 5800);
FORCEPROP 1 LAST PATH I48
J 0
(-7150 5775);
DISPLAY 0.872340 (-7150 5775);
PAINT AQUA (-7150 5775);
DISPLAY INVISIBLE (-7150 5775);
FORCEPROP 2 LAST CDS_LIB pure_quanta_power
J 0
(-7200 5750);
DISPLAY INVISIBLE (-7200 5750);
FORCEADD Q_LED..1
R 2
(-7425 2825);
FORCEPROP 1 LAST $LOCATION D1
J 2
(-7375 2925);
DISPLAY 0.468085 (-7375 2925);
PAINT SKYBLUE (-7375 2925);
FORCEPROP 0 LAST CDS_LOCATION D1
J 0
(-7375 2975);
DISPLAY 0.680851 (-7375 2975);
DISPLAY INVISIBLE (-7375 2975);
FORCEPROP 0 LAST $SEC 1
J 0
(-7375 2975);
DISPLAY 0.680851 (-7375 2975);
PAINT MONO (-7375 2975);
DISPLAY INVISIBLE (-7375 2975);
FORCEPROP 0 LAST CDS_SEC 1
J 0
(-7375 2975);
DISPLAY 0.680851 (-7375 2975);
DISPLAY INVISIBLE (-7375 2975);
FORCEPROP 0 LASTPIN (-7275 2825) $PN A
J 0
(-7265 2835);
DISPLAY 0.680851 (-7265 2835);
PAINT MONO (-7265 2835);
FORCEPROP 0 LASTPIN (-7575 2825) $PN C
J 2
(-7585 2835);
DISPLAY 0.680851 (-7585 2835);
PAINT MONO (-7585 2835);
FORCEPROP 1 LAST PART_NUMBER BEGR0278Z00
J 2
(-7400 2900);
DISPLAY 0.382979 (-7400 2900);
PAINT SKYBLUE (-7400 2900);
FORCEPROP 1 LAST MATERIAL IC
J 2
(-7325 2905);
DISPLAY 0.382979 (-7325 2905);
PAINT SKYBLUE (-7325 2905);
FORCEPROP 2 LASTPIN (-7275 2825) SIG_NAME LED_D0_R
J 0
(-7210 2860);
DISPLAY 0.553191 (-7210 2860);
FORCEPROP 2 LASTPROP $XRERR UNIQUE?
J 0
(-7450 2860);
DISPLAY 0.638298 (-7450 2860);
PAINT MONO (-7450 2860);
DISPLAY INVISIBLE (-7450 2860);
FORCEPROP 0 LAST MANUF_PN 19-213/GVC-AMNB/3T
J 2
(-7325 3100);
DISPLAY 0.680851 (-7325 3100);
DISPLAY INVISIBLE (-7325 3100);
FORCEPROP 0 LAST COLOR LED_GREEN
J 2
(-7325 3150);
DISPLAY 0.680851 (-7325 3150);
DISPLAY INVISIBLE (-7325 3150);
FORCEPROP 0 LAST PACK_TYPE SMLF
J 2
(-7425 2925);
DISPLAY 0.680851 (-7425 2925);
DISPLAY INVISIBLE (-7425 2925);
FORCEPROP 2 LAST CDS_LIB pure_quanta
J 2
(-7425 2825);
DISPLAY INVISIBLE (-7425 2825);
FORCEPROP 1 LAST PATH I49
J 2
(-7550 2905);
DISPLAY 0.723404 (-7550 2905);
PAINT GREEN (-7550 2905);
DISPLAY INVISIBLE (-7550 2905);
FORCEPROP 1 LAST NEEDS_NO_SIZE TRUE
J 2
(-7425 2825);
DISPLAY 0.468085 (-7425 2825);
PAINT GREEN (-7425 2825);
DISPLAY INVISIBLE (-7425 2825);
FORCEADD Q_RES..2
(-3950 5425);
FORCEPROP 1 LAST LOCATION R946
J 0
(-3905 5550);
DISPLAY 0.489362 (-3905 5550);
PAINT SKYBLUE (-3905 5550);
FORCEPROP 0 LAST $SEC 1
J 0
(-3900 5600);
DISPLAY 0.680851 (-3900 5600);
PAINT MONO (-3900 5600);
DISPLAY INVISIBLE (-3900 5600);
FORCEPROP 0 LAST CDS_SEC 1
J 0
(-3900 5600);
DISPLAY 0.680851 (-3900 5600);
DISPLAY INVISIBLE (-3900 5600);
FORCEPROP 1 LASTPIN (-3950 5525) $PN 1
J 0
(-3945 5487);
DISPLAY 0.489362 (-3945 5487);
PAINT MONO (-3945 5487);
FORCEPROP 1 LASTPIN (-3950 5325) $PN 2
J 0
(-3945 5335);
DISPLAY 0.489362 (-3945 5335);
PAINT MONO (-3945 5335);
FORCEPROP 1 LAST VALUE 4.7K
J 0
(-3905 5500);
DISPLAY 0.489362 (-3905 5500);
PAINT SKYBLUE (-3905 5500);
FORCEPROP 1 LAST TOLERANCE 5%
J 0
(-3905 5450);
DISPLAY 0.489362 (-3905 5450);
PAINT SKYBLUE (-3905 5450);
FORCEPROP 1 LAST MATERIAL CHIP
J 0
(-3910 5350);
DISPLAY 0.489362 (-3910 5350);
PAINT SKYBLUE (-3910 5350);
FORCEPROP 1 LAST WATTAGE 1/16W
J 0
(-3910 5400);
DISPLAY 0.489362 (-3910 5400);
PAINT SKYBLUE (-3910 5400);
FORCEPROP 1 LAST PACK_TYPE 0402LF
J 0
(-3910 5250);
DISPLAY 0.489362 (-3910 5250);
PAINT SKYBLUE (-3910 5250);
DISPLAY INVISIBLE (-3910 5250);
FORCEPROP 1 LAST PART_NUMBER TMP_QCS24702JB38
J 0
(-3910 5300);
DISPLAY 0.489362 (-3910 5300);
PAINT SKYBLUE (-3910 5300);
DISPLAY INVISIBLE (-3910 5300);
FORCEPROP 1 LAST PATH I5
J 0
(-3900 5600);
DISPLAY 0.978723 (-3900 5600);
PAINT WHITE (-3900 5600);
DISPLAY INVISIBLE (-3900 5600);
FORCEPROP 2 LAST BOM_COST OCP3.0 
J 0
(-3900 5600);
DISPLAY 0.680851 (-3900 5600);
DISPLAY INVISIBLE (-3900 5600);
FORCEPROP 2 LAST CDS_LIB pure_quanta
J 0
(-3950 5425);
DISPLAY INVISIBLE (-3950 5425);
FORCEADD Q_LED..1
R 2
(-7425 2650);
FORCEPROP 1 LAST $LOCATION D3
J 2
(-7375 2750);
DISPLAY 0.468085 (-7375 2750);
PAINT SKYBLUE (-7375 2750);
FORCEPROP 0 LAST CDS_LOCATION D3
J 0
(-7375 2800);
DISPLAY 0.680851 (-7375 2800);
DISPLAY INVISIBLE (-7375 2800);
FORCEPROP 0 LAST $SEC 1
J 0
(-7375 2800);
DISPLAY 0.680851 (-7375 2800);
PAINT MONO (-7375 2800);
DISPLAY INVISIBLE (-7375 2800);
FORCEPROP 0 LAST CDS_SEC 1
J 0
(-7375 2800);
DISPLAY 0.680851 (-7375 2800);
DISPLAY INVISIBLE (-7375 2800);
FORCEPROP 0 LASTPIN (-7275 2650) $PN A
J 0
(-7265 2660);
DISPLAY 0.680851 (-7265 2660);
PAINT MONO (-7265 2660);
FORCEPROP 0 LASTPIN (-7575 2650) $PN C
J 2
(-7585 2660);
DISPLAY 0.680851 (-7585 2660);
PAINT MONO (-7585 2660);
FORCEPROP 1 LAST PART_NUMBER BEGR0278Z00
J 2
(-7400 2725);
DISPLAY 0.382979 (-7400 2725);
PAINT SKYBLUE (-7400 2725);
FORCEPROP 1 LAST MATERIAL IC
J 2
(-7325 2730);
DISPLAY 0.382979 (-7325 2730);
PAINT SKYBLUE (-7325 2730);
FORCEPROP 0 LAST MANUF_PN 19-213/GVC-AMNB/3T
J 2
(-7325 2925);
DISPLAY 0.680851 (-7325 2925);
DISPLAY INVISIBLE (-7325 2925);
FORCEPROP 0 LAST COLOR LED_GREEN
J 2
(-7325 2975);
DISPLAY 0.680851 (-7325 2975);
DISPLAY INVISIBLE (-7325 2975);
FORCEPROP 0 LAST PACK_TYPE SMLF
J 2
(-7425 2750);
DISPLAY 0.680851 (-7425 2750);
DISPLAY INVISIBLE (-7425 2750);
FORCEPROP 2 LAST CDS_LIB pure_quanta
J 0
(-7425 2650);
DISPLAY INVISIBLE (-7425 2650);
FORCEPROP 1 LAST PATH I50
J 2
(-7550 2730);
DISPLAY 0.723404 (-7550 2730);
PAINT GREEN (-7550 2730);
DISPLAY INVISIBLE (-7550 2730);
FORCEPROP 1 LAST NEEDS_NO_SIZE TRUE
J 2
(-7425 2650);
DISPLAY 0.468085 (-7425 2650);
PAINT GREEN (-7425 2650);
DISPLAY INVISIBLE (-7425 2650);
FORCEADD Q_LED..1
R 2
(-7425 2450);
FORCEPROP 1 LAST $LOCATION D10
J 2
(-7375 2550);
DISPLAY 0.468085 (-7375 2550);
PAINT SKYBLUE (-7375 2550);
FORCEPROP 0 LAST CDS_LOCATION D10
J 0
(-7375 2600);
DISPLAY 0.680851 (-7375 2600);
DISPLAY INVISIBLE (-7375 2600);
FORCEPROP 0 LAST $SEC 1
J 0
(-7375 2600);
DISPLAY 0.680851 (-7375 2600);
PAINT MONO (-7375 2600);
DISPLAY INVISIBLE (-7375 2600);
FORCEPROP 0 LAST CDS_SEC 1
J 0
(-7375 2600);
DISPLAY 0.680851 (-7375 2600);
DISPLAY INVISIBLE (-7375 2600);
FORCEPROP 0 LASTPIN (-7275 2450) $PN A
J 0
(-7265 2460);
DISPLAY 0.680851 (-7265 2460);
PAINT MONO (-7265 2460);
FORCEPROP 0 LASTPIN (-7575 2450) $PN C
J 2
(-7585 2460);
DISPLAY 0.680851 (-7585 2460);
PAINT MONO (-7585 2460);
FORCEPROP 1 LAST PART_NUMBER BEGR0278Z00
J 2
(-7400 2525);
DISPLAY 0.382979 (-7400 2525);
PAINT SKYBLUE (-7400 2525);
FORCEPROP 1 LAST MATERIAL IC
J 2
(-7325 2530);
DISPLAY 0.382979 (-7325 2530);
PAINT SKYBLUE (-7325 2530);
FORCEPROP 0 LAST MANUF_PN 19-213/GVC-AMNB/3T
J 2
(-7325 2725);
DISPLAY 0.680851 (-7325 2725);
DISPLAY INVISIBLE (-7325 2725);
FORCEPROP 0 LAST COLOR LED_GREEN
J 2
(-7325 2775);
DISPLAY 0.680851 (-7325 2775);
DISPLAY INVISIBLE (-7325 2775);
FORCEPROP 0 LAST PACK_TYPE SMLF
J 2
(-7425 2550);
DISPLAY 0.680851 (-7425 2550);
DISPLAY INVISIBLE (-7425 2550);
FORCEPROP 2 LAST CDS_LIB pure_quanta
J 0
(-7425 2450);
DISPLAY INVISIBLE (-7425 2450);
FORCEPROP 1 LAST PATH I51
J 2
(-7550 2530);
DISPLAY 0.723404 (-7550 2530);
PAINT GREEN (-7550 2530);
DISPLAY INVISIBLE (-7550 2530);
FORCEPROP 1 LAST NEEDS_NO_SIZE TRUE
J 2
(-7425 2450);
DISPLAY 0.468085 (-7425 2450);
PAINT GREEN (-7425 2450);
DISPLAY INVISIBLE (-7425 2450);
FORCEADD Q_LED..1
R 2
(-7425 2250);
FORCEPROP 1 LAST $LOCATION D11
J 2
(-7375 2350);
DISPLAY 0.468085 (-7375 2350);
PAINT SKYBLUE (-7375 2350);
FORCEPROP 0 LAST CDS_LOCATION D11
J 0
(-7375 2400);
DISPLAY 0.680851 (-7375 2400);
DISPLAY INVISIBLE (-7375 2400);
FORCEPROP 0 LAST $SEC 1
J 0
(-7375 2400);
DISPLAY 0.680851 (-7375 2400);
PAINT MONO (-7375 2400);
DISPLAY INVISIBLE (-7375 2400);
FORCEPROP 0 LAST CDS_SEC 1
J 0
(-7375 2400);
DISPLAY 0.680851 (-7375 2400);
DISPLAY INVISIBLE (-7375 2400);
FORCEPROP 0 LASTPIN (-7275 2250) $PN A
J 0
(-7265 2260);
DISPLAY 0.680851 (-7265 2260);
PAINT MONO (-7265 2260);
FORCEPROP 0 LASTPIN (-7575 2250) $PN C
J 2
(-7585 2260);
DISPLAY 0.680851 (-7585 2260);
PAINT MONO (-7585 2260);
FORCEPROP 1 LAST PART_NUMBER BEGR0278Z00
J 2
(-7400 2325);
DISPLAY 0.382979 (-7400 2325);
PAINT SKYBLUE (-7400 2325);
FORCEPROP 1 LAST MATERIAL IC
J 2
(-7325 2330);
DISPLAY 0.382979 (-7325 2330);
PAINT SKYBLUE (-7325 2330);
FORCEPROP 0 LAST MANUF_PN 19-213/GVC-AMNB/3T
J 2
(-7325 2525);
DISPLAY 0.680851 (-7325 2525);
DISPLAY INVISIBLE (-7325 2525);
FORCEPROP 0 LAST COLOR LED_GREEN
J 2
(-7325 2575);
DISPLAY 0.680851 (-7325 2575);
DISPLAY INVISIBLE (-7325 2575);
FORCEPROP 0 LAST PACK_TYPE SMLF
J 2
(-7425 2350);
DISPLAY 0.680851 (-7425 2350);
DISPLAY INVISIBLE (-7425 2350);
FORCEPROP 2 LAST CDS_LIB pure_quanta
J 0
(-7425 2250);
DISPLAY INVISIBLE (-7425 2250);
FORCEPROP 1 LAST PATH I52
J 2
(-7550 2330);
DISPLAY 0.723404 (-7550 2330);
PAINT GREEN (-7550 2330);
DISPLAY INVISIBLE (-7550 2330);
FORCEPROP 1 LAST NEEDS_NO_SIZE TRUE
J 2
(-7425 2250);
DISPLAY 0.468085 (-7425 2250);
PAINT GREEN (-7425 2250);
DISPLAY INVISIBLE (-7425 2250);
FORCEADD P1V0..1
(-6425 3075);
FORCEPROP 3 LASTPIN (-6425 3025) SIG_NAME P3V3_STBY\g
J 0
(-6415 3035);
DISPLAY 0.659574 (-6415 3035);
PAINT MONO (-6415 3035);
DISPLAY INVISIBLE (-6415 3035);
FORCEPROP 1 LAST HDL_POWER P3V3_STBY
J 1
(-6425 3125);
DISPLAY 0.489362 (-6425 3125);
PAINT GREEN (-6425 3125);
FORCEPROP 1 LAST PATH I53
J 0
(-6375 3100);
DISPLAY 0.872340 (-6375 3100);
PAINT AQUA (-6375 3100);
DISPLAY INVISIBLE (-6375 3100);
FORCEPROP 2 LAST CDS_LIB pure_quanta_power
J 0
(-6425 3075);
DISPLAY INVISIBLE (-6425 3075);
FORCEADD Q_RES..1
(-6750 2825);
FORCEPROP 1 LAST $LOCATION R1075
J 0
(-6775 2850);
DISPLAY 0.404255 (-6775 2850);
PAINT SKYBLUE (-6775 2850);
FORCEPROP 0 LAST CDS_LOCATION R1075
J 0
(-6850 2925);
DISPLAY 0.680851 (-6850 2925);
DISPLAY INVISIBLE (-6850 2925);
FORCEPROP 0 LAST $SEC 1
J 0
(-6850 2925);
DISPLAY 0.680851 (-6850 2925);
PAINT MONO (-6850 2925);
DISPLAY INVISIBLE (-6850 2925);
FORCEPROP 0 LAST CDS_SEC 1
J 0
(-6850 2925);
DISPLAY 0.680851 (-6850 2925);
DISPLAY INVISIBLE (-6850 2925);
FORCEPROP 1 LASTPIN (-6850 2825) $PN 1
J 0
(-6838 2837);
DISPLAY 0.787234 (-6838 2837);
PAINT MONO (-6838 2837);
FORCEPROP 1 LASTPIN (-6650 2825) $PN 2
J 0
(-6688 2837);
DISPLAY 0.787234 (-6688 2837);
PAINT MONO (-6688 2837);
FORCEPROP 1 LAST MATERIAL CHIP
J 0
(-6650 2850);
DISPLAY 0.404255 (-6650 2850);
PAINT SKYBLUE (-6650 2850);
FORCEPROP 1 LAST VALUE 200
J 2
(-6825 2850);
DISPLAY 0.404255 (-6825 2850);
PAINT SKYBLUE (-6825 2850);
FORCEPROP 1 LAST PART_NUMBER CS12002FB06
J 0
(-6850 2900);
DISPLAY 0.404255 (-6850 2900);
PAINT SKYBLUE (-6850 2900);
FORCEPROP 1 LAST PACK_TYPE 0402LF
J 0
(-6500 2675);
DISPLAY 0.978723 (-6500 2675);
DISPLAY INVISIBLE (-6500 2675);
FORCEPROP 1 LAST TOLERANCE 1%
J 0
(-6750 2725);
DISPLAY 0.978723 (-6750 2725);
DISPLAY INVISIBLE (-6750 2725);
FORCEPROP 1 LAST WATTAGE 1/16W
J 2
(-6775 2675);
DISPLAY 0.978723 (-6775 2675);
DISPLAY INVISIBLE (-6775 2675);
FORCEPROP 1 LAST PATH I54
J 0
(-6800 2975);
DISPLAY 0.978723 (-6800 2975);
PAINT WHITE (-6800 2975);
DISPLAY INVISIBLE (-6800 2975);
FORCEPROP 2 LAST CDS_LIB pure_quanta
J 0
(-6750 2825);
DISPLAY INVISIBLE (-6750 2825);
FORCEADD Q_RES..1
(-6750 2650);
FORCEPROP 1 LAST $LOCATION R1076
J 0
(-6775 2675);
DISPLAY 0.404255 (-6775 2675);
PAINT SKYBLUE (-6775 2675);
FORCEPROP 0 LAST CDS_LOCATION R1076
J 0
(-6850 2750);
DISPLAY 0.680851 (-6850 2750);
DISPLAY INVISIBLE (-6850 2750);
FORCEPROP 0 LAST $SEC 1
J 0
(-6850 2750);
DISPLAY 0.680851 (-6850 2750);
PAINT MONO (-6850 2750);
DISPLAY INVISIBLE (-6850 2750);
FORCEPROP 0 LAST CDS_SEC 1
J 0
(-6850 2750);
DISPLAY 0.680851 (-6850 2750);
DISPLAY INVISIBLE (-6850 2750);
FORCEPROP 1 LASTPIN (-6850 2650) $PN 1
J 0
(-6838 2662);
DISPLAY 0.787234 (-6838 2662);
PAINT MONO (-6838 2662);
FORCEPROP 1 LASTPIN (-6650 2650) $PN 2
J 0
(-6688 2662);
DISPLAY 0.787234 (-6688 2662);
PAINT MONO (-6688 2662);
FORCEPROP 1 LAST PART_NUMBER CS12002FB06
J 0
(-6850 2725);
DISPLAY 0.404255 (-6850 2725);
PAINT SKYBLUE (-6850 2725);
FORCEPROP 1 LAST MATERIAL CHIP
J 0
(-6650 2675);
DISPLAY 0.404255 (-6650 2675);
PAINT SKYBLUE (-6650 2675);
FORCEPROP 1 LAST VALUE 200
J 2
(-6825 2675);
DISPLAY 0.404255 (-6825 2675);
PAINT SKYBLUE (-6825 2675);
FORCEPROP 1 LAST PACK_TYPE 0402LF
J 0
(-6500 2500);
DISPLAY 0.978723 (-6500 2500);
DISPLAY INVISIBLE (-6500 2500);
FORCEPROP 1 LAST TOLERANCE 1%
J 0
(-6750 2550);
DISPLAY 0.978723 (-6750 2550);
DISPLAY INVISIBLE (-6750 2550);
FORCEPROP 1 LAST WATTAGE 1/16W
J 2
(-6775 2500);
DISPLAY 0.978723 (-6775 2500);
DISPLAY INVISIBLE (-6775 2500);
FORCEPROP 1 LAST PATH I55
J 0
(-6800 2800);
DISPLAY 0.978723 (-6800 2800);
PAINT WHITE (-6800 2800);
DISPLAY INVISIBLE (-6800 2800);
FORCEPROP 2 LAST CDS_LIB pure_quanta
J 0
(-6750 2650);
DISPLAY INVISIBLE (-6750 2650);
FORCEADD Q_RES..1
(-6750 2450);
FORCEPROP 1 LAST $LOCATION R1102
J 0
(-6775 2475);
DISPLAY 0.404255 (-6775 2475);
PAINT SKYBLUE (-6775 2475);
FORCEPROP 0 LAST CDS_LOCATION R1102
J 0
(-6850 2550);
DISPLAY 0.680851 (-6850 2550);
DISPLAY INVISIBLE (-6850 2550);
FORCEPROP 0 LAST $SEC 1
J 0
(-6850 2550);
DISPLAY 0.680851 (-6850 2550);
PAINT MONO (-6850 2550);
DISPLAY INVISIBLE (-6850 2550);
FORCEPROP 0 LAST CDS_SEC 1
J 0
(-6850 2550);
DISPLAY 0.680851 (-6850 2550);
DISPLAY INVISIBLE (-6850 2550);
FORCEPROP 1 LASTPIN (-6850 2450) $PN 1
J 0
(-6838 2462);
DISPLAY 0.787234 (-6838 2462);
PAINT MONO (-6838 2462);
FORCEPROP 1 LASTPIN (-6650 2450) $PN 2
J 0
(-6688 2462);
DISPLAY 0.787234 (-6688 2462);
PAINT MONO (-6688 2462);
FORCEPROP 1 LAST MATERIAL CHIP
J 0
(-6650 2475);
DISPLAY 0.404255 (-6650 2475);
PAINT SKYBLUE (-6650 2475);
FORCEPROP 1 LAST VALUE 200
J 2
(-6825 2475);
DISPLAY 0.404255 (-6825 2475);
PAINT SKYBLUE (-6825 2475);
FORCEPROP 1 LAST PART_NUMBER CS12002FB06
J 0
(-6850 2525);
DISPLAY 0.404255 (-6850 2525);
PAINT SKYBLUE (-6850 2525);
FORCEPROP 1 LAST WATTAGE 1/16W
J 2
(-6775 2300);
DISPLAY 0.978723 (-6775 2300);
DISPLAY INVISIBLE (-6775 2300);
FORCEPROP 1 LAST TOLERANCE 1%
J 0
(-6750 2350);
DISPLAY 0.978723 (-6750 2350);
DISPLAY INVISIBLE (-6750 2350);
FORCEPROP 1 LAST PACK_TYPE 0402LF
J 0
(-6500 2300);
DISPLAY 0.978723 (-6500 2300);
DISPLAY INVISIBLE (-6500 2300);
FORCEPROP 1 LAST PATH I56
J 0
(-6800 2600);
DISPLAY 0.978723 (-6800 2600);
PAINT WHITE (-6800 2600);
DISPLAY INVISIBLE (-6800 2600);
FORCEPROP 2 LAST CDS_LIB pure_quanta
J 0
(-6750 2450);
DISPLAY INVISIBLE (-6750 2450);
FORCEADD Q_RES..1
(-6750 2250);
FORCEPROP 1 LAST $LOCATION R1103
J 0
(-6775 2275);
DISPLAY 0.404255 (-6775 2275);
PAINT SKYBLUE (-6775 2275);
FORCEPROP 0 LAST CDS_LOCATION R1103
J 0
(-6850 2350);
DISPLAY 0.680851 (-6850 2350);
DISPLAY INVISIBLE (-6850 2350);
FORCEPROP 0 LAST $SEC 1
J 0
(-6850 2350);
DISPLAY 0.680851 (-6850 2350);
PAINT MONO (-6850 2350);
DISPLAY INVISIBLE (-6850 2350);
FORCEPROP 0 LAST CDS_SEC 1
J 0
(-6850 2350);
DISPLAY 0.680851 (-6850 2350);
DISPLAY INVISIBLE (-6850 2350);
FORCEPROP 1 LASTPIN (-6850 2250) $PN 1
J 0
(-6838 2262);
DISPLAY 0.787234 (-6838 2262);
PAINT MONO (-6838 2262);
FORCEPROP 1 LASTPIN (-6650 2250) $PN 2
J 0
(-6688 2262);
DISPLAY 0.787234 (-6688 2262);
PAINT MONO (-6688 2262);
FORCEPROP 1 LAST PART_NUMBER CS12002FB06
J 0
(-6850 2325);
DISPLAY 0.404255 (-6850 2325);
PAINT SKYBLUE (-6850 2325);
FORCEPROP 1 LAST VALUE 200
J 2
(-6825 2275);
DISPLAY 0.404255 (-6825 2275);
PAINT SKYBLUE (-6825 2275);
FORCEPROP 1 LAST MATERIAL CHIP
J 0
(-6650 2275);
DISPLAY 0.404255 (-6650 2275);
PAINT SKYBLUE (-6650 2275);
FORCEPROP 1 LAST WATTAGE 1/16W
J 2
(-6775 2100);
DISPLAY 0.978723 (-6775 2100);
DISPLAY INVISIBLE (-6775 2100);
FORCEPROP 1 LAST TOLERANCE 1%
J 0
(-6750 2150);
DISPLAY 0.978723 (-6750 2150);
DISPLAY INVISIBLE (-6750 2150);
FORCEPROP 1 LAST PACK_TYPE 0402LF
J 0
(-6500 2100);
DISPLAY 0.978723 (-6500 2100);
DISPLAY INVISIBLE (-6500 2100);
FORCEPROP 1 LAST PATH I57
J 0
(-6800 2400);
DISPLAY 0.978723 (-6800 2400);
PAINT WHITE (-6800 2400);
DISPLAY INVISIBLE (-6800 2400);
FORCEPROP 2 LAST CDS_LIB pure_quanta
J 0
(-6750 2250);
DISPLAY INVISIBLE (-6750 2250);
FORCEADD MOSFET_DUAL_6P..1
R 6
(-8550 2650);
FORCEPROP 1 LAST $LOCATION Q32
J 0
(-8500 2775);
DISPLAY 0.468085 (-8500 2775);
PAINT SKYBLUE (-8500 2775);
FORCEPROP 0 LAST CDS_LOCATION Q32
J 0
(-8675 2950);
DISPLAY 0.680851 (-8675 2950);
DISPLAY INVISIBLE (-8675 2950);
FORCEPROP 0 LAST $SEC 1
J 0
(-8675 2950);
DISPLAY 0.680851 (-8675 2950);
PAINT MONO (-8675 2950);
DISPLAY INVISIBLE (-8675 2950);
FORCEPROP 0 LAST CDS_SEC 1
J 0
(-8675 2950);
DISPLAY 0.680851 (-8675 2950);
DISPLAY INVISIBLE (-8675 2950);
FORCEPROP 0 LASTPIN (-8850 2700) $PN 6
J 2
(-8860 2710);
DISPLAY 0.680851 (-8860 2710);
PAINT MONO (-8860 2710);
FORCEPROP 0 LASTPIN (-8250 2700) $PN 3
J 0
(-8240 2710);
DISPLAY 0.680851 (-8240 2710);
PAINT MONO (-8240 2710);
FORCEPROP 0 LASTPIN (-8850 2650) $PN 2
J 2
(-8860 2660);
DISPLAY 0.680851 (-8860 2660);
PAINT MONO (-8860 2660);
FORCEPROP 0 LASTPIN (-8250 2650) $PN 5
J 0
(-8240 2660);
DISPLAY 0.680851 (-8240 2660);
PAINT MONO (-8240 2660);
FORCEPROP 0 LASTPIN (-8850 2600) $PN 1
J 2
(-8860 2610);
DISPLAY 0.680851 (-8860 2610);
PAINT MONO (-8860 2610);
FORCEPROP 0 LASTPIN (-8250 2600) $PN 4
J 0
(-8240 2610);
DISPLAY 0.680851 (-8240 2610);
PAINT MONO (-8240 2610);
FORCEPROP 1 LAST PART_NUMBER BAM70020047
J 0
(-8675 2850);
DISPLAY 0.468085 (-8675 2850);
PAINT SKYBLUE (-8675 2850);
FORCEPROP 1 LAST MATERIAL IC
J 0
(-8675 2775);
DISPLAY 0.468085 (-8675 2775);
PAINT SKYBLUE (-8675 2775);
FORCEPROP 0 LAST VALUE 2N7002KDW
J 0
(-8675 2368);
DISPLAY 0.680851 (-8675 2368);
DISPLAY INVISIBLE (-8675 2368);
FORCEPROP 1 LAST NEEDS_NO_SIZE TRUE
J 0
(-8550 2629);
DISPLAY 0.468085 (-8550 2629);
PAINT GREEN (-8550 2629);
DISPLAY INVISIBLE (-8550 2629);
FORCEPROP 1 LAST PATH I58
J 0
(-8550 2616);
DISPLAY 0.723404 (-8550 2616);
PAINT GREEN (-8550 2616);
DISPLAY INVISIBLE (-8550 2616);
FORCEPROP 2 LAST CDS_LIB pure_quanta
J 0
(-8550 2603);
DISPLAY INVISIBLE (-8550 2603);
FORCEPROP 1 LAST CDS_LMAN_SYM_OUTLINE -150,100,150,-100
J 0
(-8550 2628);
DISPLAY 0.468085 (-8550 2628);
PAINT GREEN (-8550 2628);
DISPLAY INVISIBLE (-8550 2628);
FORCEPROP 0 LAST PART_TYPE SMLF
J 0
(-8675 2900);
DISPLAY 0.680851 (-8675 2900);
DISPLAY INVISIBLE (-8675 2900);
FORCEADD GND..1
R 1
(-4000 5175);
FORCEPROP 3 LASTPIN (-4050 5175) SIG_NAME GND\g
J 0
(-4040 5185);
DISPLAY 0.659574 (-4040 5185);
PAINT MONO (-4040 5185);
DISPLAY INVISIBLE (-4040 5185);
FORCEPROP 1 LAST HDL_POWER GND
R 1
J 0
(-4150 5175);
DISPLAY 0.851064 (-4150 5175);
PAINT GREEN (-4150 5175);
DISPLAY INVISIBLE (-4150 5175);
FORCEPROP 1 LAST PATH I6
R 1
J 0
(-4000 5250);
DISPLAY 0.872340 (-4000 5250);
PAINT AQUA (-4000 5250);
DISPLAY INVISIBLE (-4000 5250);
FORCEPROP 2 LAST CDS_LIB pure_quanta_power
J 0
(-4000 5175);
DISPLAY INVISIBLE (-4000 5175);
FORCEPROP 2 LAST BOM_COST MEM
R 1
J 0
(-4075 5075);
DISPLAY 0.808511 (-4075 5075);
DISPLAY INVISIBLE (-4075 5075);
FORCEPROP 1 LAST SIZE 1B
R 1
J 0
(-3950 5250);
DISPLAY 0.851064 (-3950 5250);
PAINT GREEN (-3950 5250);
DISPLAY INVISIBLE (-3950 5250);
FORCEADD UNIVERSAL_GND..1
(-8950 2475);
FORCEPROP 3 LASTPIN (-8950 2525) SIG_NAME GND\g
J 0
(-8940 2535);
DISPLAY 0.659574 (-8940 2535);
PAINT MONO (-8940 2535);
DISPLAY INVISIBLE (-8940 2535);
FORCEPROP 1 LAST HDL_POWER GND
J 1
(-8925 2400);
DISPLAY 0.872340 (-8925 2400);
PAINT GREEN (-8925 2400);
DISPLAY INVISIBLE (-8925 2400);
FORCEPROP 2 LAST BOM_COST OCP3.0 
J 0
(-9150 2550);
DISPLAY 0.680851 (-9150 2550);
DISPLAY INVISIBLE (-9150 2550);
FORCEPROP 1 LAST PATH I60
J 0
(-8875 2475);
DISPLAY 0.872340 (-8875 2475);
PAINT AQUA (-8875 2475);
DISPLAY INVISIBLE (-8875 2475);
FORCEPROP 2 LAST CDS_LIB pure_quanta_power
J 0
(-8950 2475);
DISPLAY INVISIBLE (-8950 2475);
FORCEADD OFFPAGE..1
(-9350 2650);
FORCEPROP 2 LAST $XR0 80 
J 0
(-9571 2650);
DISPLAY 0.638298 (-9571 2650);
PAINT MONO (-9571 2650);
FORCEPROP 1 LAST OFFPAGE TRUE
J 0
(-9025 2525);
DISPLAY 0.872340 (-9025 2525);
PAINT GREEN (-9025 2525);
DISPLAY INVISIBLE (-9025 2525);
FORCEPROP 1 LAST COMMENT_BODY TRUE
J 0
(-9225 2550);
DISPLAY 0.872340 (-9225 2550);
PAINT GREEN (-9225 2550);
DISPLAY INVISIBLE (-9225 2550);
FORCEPROP 2 LAST PATH I61
J 0
(-9300 2725);
DISPLAY 0.680851 (-9300 2725);
DISPLAY INVISIBLE (-9300 2725);
FORCEPROP 2 LAST CDS_LIB standard
J 0
(-9350 2650);
DISPLAY INVISIBLE (-9350 2650);
FORCEADD MOSFET_DUAL_6P..1
R 6
(-8525 2200);
FORCEPROP 1 LAST $LOCATION Q33
J 0
(-8500 2325);
DISPLAY 0.468085 (-8500 2325);
PAINT SKYBLUE (-8500 2325);
FORCEPROP 0 LAST CDS_LOCATION Q33
J 0
(-8650 2500);
DISPLAY 0.680851 (-8650 2500);
DISPLAY INVISIBLE (-8650 2500);
FORCEPROP 0 LAST $SEC 1
J 0
(-8650 2500);
DISPLAY 0.680851 (-8650 2500);
PAINT MONO (-8650 2500);
DISPLAY INVISIBLE (-8650 2500);
FORCEPROP 0 LAST CDS_SEC 1
J 0
(-8650 2500);
DISPLAY 0.680851 (-8650 2500);
DISPLAY INVISIBLE (-8650 2500);
FORCEPROP 0 LASTPIN (-8825 2250) $PN 6
J 2
(-8835 2260);
DISPLAY 0.680851 (-8835 2260);
PAINT MONO (-8835 2260);
FORCEPROP 0 LASTPIN (-8225 2250) $PN 3
J 0
(-8215 2260);
DISPLAY 0.680851 (-8215 2260);
PAINT MONO (-8215 2260);
FORCEPROP 0 LASTPIN (-8825 2200) $PN 2
J 2
(-8835 2210);
DISPLAY 0.680851 (-8835 2210);
PAINT MONO (-8835 2210);
FORCEPROP 0 LASTPIN (-8225 2200) $PN 5
J 0
(-8215 2210);
DISPLAY 0.680851 (-8215 2210);
PAINT MONO (-8215 2210);
FORCEPROP 0 LASTPIN (-8825 2150) $PN 1
J 2
(-8835 2160);
DISPLAY 0.680851 (-8835 2160);
PAINT MONO (-8835 2160);
FORCEPROP 0 LASTPIN (-8225 2150) $PN 4
J 0
(-8215 2160);
DISPLAY 0.680851 (-8215 2160);
PAINT MONO (-8215 2160);
FORCEPROP 1 LAST PART_NUMBER BAM70020047
J 0
(-8650 2400);
DISPLAY 0.468085 (-8650 2400);
PAINT SKYBLUE (-8650 2400);
FORCEPROP 1 LAST MATERIAL IC
J 0
(-8650 2325);
DISPLAY 0.468085 (-8650 2325);
PAINT SKYBLUE (-8650 2325);
FORCEPROP 0 LAST VALUE 2N7002KDW
J 0
(-8650 1918);
DISPLAY 0.680851 (-8650 1918);
DISPLAY INVISIBLE (-8650 1918);
FORCEPROP 1 LAST NEEDS_NO_SIZE TRUE
J 0
(-8525 2179);
DISPLAY 0.468085 (-8525 2179);
PAINT GREEN (-8525 2179);
DISPLAY INVISIBLE (-8525 2179);
FORCEPROP 1 LAST PATH I62
J 0
(-8525 2200);
DISPLAY 0.723404 (-8525 2200);
PAINT GREEN (-8525 2200);
DISPLAY INVISIBLE (-8525 2200);
FORCEPROP 2 LAST CDS_LIB pure_quanta
J 0
(-8525 2200);
DISPLAY INVISIBLE (-8525 2200);
FORCEPROP 1 LAST CDS_LMAN_SYM_OUTLINE -150,100,150,-100
J 0
(-8525 2200);
DISPLAY 0.468085 (-8525 2200);
PAINT GREEN (-8525 2200);
DISPLAY INVISIBLE (-8525 2200);
FORCEPROP 0 LAST PART_TYPE SMLF
J 0
(-8650 2450);
DISPLAY 0.680851 (-8650 2450);
DISPLAY INVISIBLE (-8650 2450);
FORCEADD OFFPAGE..1
(-9350 2400);
FORCEPROP 2 LAST $XR0 80 
J 0
(-9571 2400);
DISPLAY 0.638298 (-9571 2400);
PAINT MONO (-9571 2400);
FORCEPROP 1 LAST COMMENT_BODY TRUE
J 0
(-9225 2300);
DISPLAY 0.872340 (-9225 2300);
PAINT GREEN (-9225 2300);
DISPLAY INVISIBLE (-9225 2300);
FORCEPROP 1 LAST OFFPAGE TRUE
J 0
(-9025 2275);
DISPLAY 0.872340 (-9025 2275);
PAINT GREEN (-9025 2275);
DISPLAY INVISIBLE (-9025 2275);
FORCEPROP 2 LAST PATH I63
J 0
(-9300 2475);
DISPLAY 0.680851 (-9300 2475);
DISPLAY INVISIBLE (-9300 2475);
FORCEPROP 2 LAST CDS_LIB standard
J 0
(-9350 2400);
DISPLAY INVISIBLE (-9350 2400);
FORCEADD UNIVERSAL_GND..1
(-8075 1825);
FORCEPROP 3 LASTPIN (-8075 1875) SIG_NAME GND\g
J 0
(-8065 1885);
DISPLAY 0.659574 (-8065 1885);
PAINT MONO (-8065 1885);
DISPLAY INVISIBLE (-8065 1885);
FORCEPROP 1 LAST HDL_POWER GND
J 1
(-8050 1750);
DISPLAY 0.872340 (-8050 1750);
PAINT GREEN (-8050 1750);
DISPLAY INVISIBLE (-8050 1750);
FORCEPROP 2 LAST BOM_COST OCP3.0 
J 0
(-8275 1900);
DISPLAY 0.680851 (-8275 1900);
DISPLAY INVISIBLE (-8275 1900);
FORCEPROP 1 LAST PATH I64
J 0
(-8000 1825);
DISPLAY 0.872340 (-8000 1825);
PAINT AQUA (-8000 1825);
DISPLAY INVISIBLE (-8000 1825);
FORCEPROP 2 LAST CDS_LIB pure_quanta_power
J 0
(-8075 1825);
DISPLAY INVISIBLE (-8075 1825);
FORCEADD OFFPAGE..1
(-9350 2200);
FORCEPROP 2 LAST $XR0 80 
J 0
(-9571 2200);
DISPLAY 0.638298 (-9571 2200);
PAINT MONO (-9571 2200);
FORCEPROP 1 LAST OFFPAGE TRUE
J 0
(-9025 2075);
DISPLAY 0.872340 (-9025 2075);
PAINT GREEN (-9025 2075);
DISPLAY INVISIBLE (-9025 2075);
FORCEPROP 1 LAST COMMENT_BODY TRUE
J 0
(-9225 2100);
DISPLAY 0.872340 (-9225 2100);
PAINT GREEN (-9225 2100);
DISPLAY INVISIBLE (-9225 2100);
FORCEPROP 2 LAST PATH I65
J 0
(-9300 2275);
DISPLAY 0.680851 (-9300 2275);
DISPLAY INVISIBLE (-9300 2275);
FORCEPROP 2 LAST CDS_LIB standard
J 0
(-9350 2200);
DISPLAY INVISIBLE (-9350 2200);
FORCEADD OFFPAGE..1
(-9350 1950);
FORCEPROP 2 LAST $XR0 80 
J 0
(-9571 1950);
DISPLAY 0.638298 (-9571 1950);
PAINT MONO (-9571 1950);
FORCEPROP 1 LAST COMMENT_BODY TRUE
J 0
(-9225 1850);
DISPLAY 0.872340 (-9225 1850);
PAINT GREEN (-9225 1850);
DISPLAY INVISIBLE (-9225 1850);
FORCEPROP 1 LAST OFFPAGE TRUE
J 0
(-9025 1825);
DISPLAY 0.872340 (-9025 1825);
PAINT GREEN (-9025 1825);
DISPLAY INVISIBLE (-9025 1825);
FORCEPROP 2 LAST PATH I66
J 0
(-9300 2025);
DISPLAY 0.680851 (-9300 2025);
DISPLAY INVISIBLE (-9300 2025);
FORCEPROP 2 LAST CDS_LIB standard
J 0
(-9350 1950);
DISPLAY INVISIBLE (-9350 1950);
FORCEADD UNIVERSAL_GND..1
(-8925 2000);
FORCEPROP 3 LASTPIN (-8925 2050) SIG_NAME GND\g
J 0
(-8915 2060);
DISPLAY 0.659574 (-8915 2060);
PAINT MONO (-8915 2060);
DISPLAY INVISIBLE (-8915 2060);
FORCEPROP 1 LAST HDL_POWER GND
J 1
(-8900 1925);
DISPLAY 0.872340 (-8900 1925);
PAINT GREEN (-8900 1925);
DISPLAY INVISIBLE (-8900 1925);
FORCEPROP 2 LAST BOM_COST OCP3.0 
J 0
(-9125 2075);
DISPLAY 0.680851 (-9125 2075);
DISPLAY INVISIBLE (-9125 2075);
FORCEPROP 1 LAST PATH I67
J 0
(-8850 2000);
DISPLAY 0.872340 (-8850 2000);
PAINT AQUA (-8850 2000);
DISPLAY INVISIBLE (-8850 2000);
FORCEPROP 2 LAST CDS_LIB pure_quanta_power
J 0
(-8925 2000);
DISPLAY INVISIBLE (-8925 2000);
FORCEADD Q_LED..1
R 2
(-7400 925);
FORCEPROP 1 LAST $LOCATION D32
J 2
(-7275 975);
DISPLAY 0.468085 (-7275 975);
PAINT SKYBLUE (-7275 975);
FORCEPROP 0 LAST CDS_LOCATION D32
J 0
(-7400 1075);
DISPLAY 0.680851 (-7400 1075);
DISPLAY INVISIBLE (-7400 1075);
FORCEPROP 0 LAST $SEC 1
J 0
(-7400 1075);
DISPLAY 0.680851 (-7400 1075);
PAINT MONO (-7400 1075);
DISPLAY INVISIBLE (-7400 1075);
FORCEPROP 0 LAST CDS_SEC 1
J 0
(-7400 1075);
DISPLAY 0.680851 (-7400 1075);
DISPLAY INVISIBLE (-7400 1075);
FORCEPROP 0 LASTPIN (-7250 925) $PN A
J 0
(-7240 935);
DISPLAY 0.680851 (-7240 935);
PAINT MONO (-7240 935);
FORCEPROP 0 LASTPIN (-7550 925) $PN C
J 2
(-7560 935);
DISPLAY 0.680851 (-7560 935);
PAINT MONO (-7560 935);
FORCEPROP 1 LAST MATERIAL IC
J 2
(-7300 1005);
DISPLAY 0.468085 (-7300 1005);
PAINT SKYBLUE (-7300 1005);
FORCEPROP 1 LAST PART_NUMBER BEGR0278Z00
J 2
(-7375 1000);
DISPLAY 0.382979 (-7375 1000);
PAINT SKYBLUE (-7375 1000);
FORCEPROP 0 LAST MANUF_PN 19-213/GVC-AMNB/3T
J 2
(-7300 1200);
DISPLAY 0.680851 (-7300 1200);
DISPLAY INVISIBLE (-7300 1200);
FORCEPROP 0 LAST COLOR LED_GREEN
J 2
(-7300 1250);
DISPLAY 0.680851 (-7300 1250);
DISPLAY INVISIBLE (-7300 1250);
FORCEPROP 0 LAST PACK_TYPE SMLF
J 2
(-7400 1025);
DISPLAY 0.680851 (-7400 1025);
DISPLAY INVISIBLE (-7400 1025);
FORCEPROP 1 LAST NEEDS_NO_SIZE TRUE
J 2
(-7400 925);
DISPLAY 0.468085 (-7400 925);
PAINT GREEN (-7400 925);
DISPLAY INVISIBLE (-7400 925);
FORCEPROP 1 LAST PATH I68
J 2
(-7525 1005);
DISPLAY 0.723404 (-7525 1005);
PAINT GREEN (-7525 1005);
DISPLAY INVISIBLE (-7525 1005);
FORCEPROP 2 LAST CDS_LIB pure_quanta
J 0
(-7400 925);
DISPLAY INVISIBLE (-7400 925);
FORCEADD MOSFET_DUAL_6P..1
R 6
(-8500 675);
FORCEPROP 1 LAST $LOCATION Q37
J 0
(-8525 800);
DISPLAY 0.468085 (-8525 800);
PAINT SKYBLUE (-8525 800);
FORCEPROP 0 LAST CDS_LOCATION Q37
J 0
(-8625 975);
DISPLAY 0.680851 (-8625 975);
DISPLAY INVISIBLE (-8625 975);
FORCEPROP 0 LAST $SEC 1
J 0
(-8625 975);
DISPLAY 0.680851 (-8625 975);
PAINT MONO (-8625 975);
DISPLAY INVISIBLE (-8625 975);
FORCEPROP 0 LAST CDS_SEC 1
J 0
(-8625 975);
DISPLAY 0.680851 (-8625 975);
DISPLAY INVISIBLE (-8625 975);
FORCEPROP 0 LASTPIN (-8800 725) $PN 6
J 2
(-8810 735);
DISPLAY 0.680851 (-8810 735);
PAINT MONO (-8810 735);
FORCEPROP 0 LASTPIN (-8200 725) $PN 3
J 0
(-8190 735);
DISPLAY 0.680851 (-8190 735);
PAINT MONO (-8190 735);
FORCEPROP 0 LASTPIN (-8800 675) $PN 2
J 2
(-8810 685);
DISPLAY 0.680851 (-8810 685);
PAINT MONO (-8810 685);
FORCEPROP 0 LASTPIN (-8200 675) $PN 5
J 0
(-8190 685);
DISPLAY 0.680851 (-8190 685);
PAINT MONO (-8190 685);
FORCEPROP 0 LASTPIN (-8800 625) $PN 1
J 2
(-8810 635);
DISPLAY 0.680851 (-8810 635);
PAINT MONO (-8810 635);
FORCEPROP 0 LASTPIN (-8200 625) $PN 4
J 0
(-8190 635);
DISPLAY 0.680851 (-8190 635);
PAINT MONO (-8190 635);
FORCEPROP 1 LAST PART_NUMBER BAM70020047
J 0
(-8625 875);
DISPLAY 0.468085 (-8625 875);
PAINT SKYBLUE (-8625 875);
FORCEPROP 1 LAST MATERIAL IC
J 0
(-8625 800);
DISPLAY 0.468085 (-8625 800);
PAINT SKYBLUE (-8625 800);
FORCEPROP 2 LAST CDS_LIB pure_quanta
J 0
(-8500 675);
DISPLAY INVISIBLE (-8500 675);
FORCEPROP 1 LAST PATH I69
J 0
(-8500 675);
DISPLAY 0.723404 (-8500 675);
PAINT GREEN (-8500 675);
DISPLAY INVISIBLE (-8500 675);
FORCEPROP 1 LAST CDS_LMAN_SYM_OUTLINE -150,100,150,-100
J 0
(-8500 675);
DISPLAY 0.468085 (-8500 675);
PAINT GREEN (-8500 675);
DISPLAY INVISIBLE (-8500 675);
FORCEPROP 1 LAST NEEDS_NO_SIZE TRUE
J 0
(-8500 654);
DISPLAY 0.468085 (-8500 654);
PAINT GREEN (-8500 654);
DISPLAY INVISIBLE (-8500 654);
FORCEPROP 0 LAST VALUE 2N7002KDW
J 0
(-8625 393);
DISPLAY 0.680851 (-8625 393);
DISPLAY INVISIBLE (-8625 393);
FORCEPROP 0 LAST PART_TYPE SMLF
J 0
(-8625 925);
DISPLAY 0.680851 (-8625 925);
DISPLAY INVISIBLE (-8625 925);
FORCEADD Q_RES..1
(-2000 5075);
FORCEPROP 1 LAST LOCATION R948
J 0
(-2150 5100);
DISPLAY 0.489362 (-2150 5100);
PAINT SKYBLUE (-2150 5100);
FORCEPROP 0 LAST $SEC 1
J 0
(-2150 5150);
DISPLAY 0.680851 (-2150 5150);
PAINT MONO (-2150 5150);
DISPLAY INVISIBLE (-2150 5150);
FORCEPROP 0 LAST CDS_SEC 1
J 0
(-2150 5150);
DISPLAY 0.680851 (-2150 5150);
DISPLAY INVISIBLE (-2150 5150);
FORCEPROP 1 LASTPIN (-2100 5075) $PN 1
J 0
(-2088 5087);
DISPLAY 0.489362 (-2088 5087);
PAINT MONO (-2088 5087);
FORCEPROP 1 LASTPIN (-1900 5075) $PN 2
J 0
(-1938 5087);
DISPLAY 0.489362 (-1938 5087);
PAINT MONO (-1938 5087);
FORCEPROP 1 LAST PACK_TYPE 0402LF
J 0
(-1775 5000);
DISPLAY 0.489362 (-1775 5000);
PAINT SKYBLUE (-1775 5000);
FORCEPROP 1 LAST VALUE 200
J 2
(-2150 5000);
DISPLAY 0.489362 (-2150 5000);
PAINT SKYBLUE (-2150 5000);
FORCEPROP 1 LAST TOLERANCE 1%
J 0
(-2125 5000);
DISPLAY 0.489362 (-2125 5000);
PAINT SKYBLUE (-2125 5000);
FORCEPROP 1 LAST MATERIAL CHIP
J 0
(-1900 5000);
DISPLAY 0.489362 (-1900 5000);
PAINT SKYBLUE (-1900 5000);
FORCEPROP 1 LAST WATTAGE 1/16W
J 2
(-1925 5000);
DISPLAY 0.489362 (-1925 5000);
PAINT SKYBLUE (-1925 5000);
FORCEPROP 1 LAST PART_NUMBER CS12002FB06
J 0
(-1975 5125);
DISPLAY 0.638298 (-1975 5125);
PAINT SKYBLUE (-1975 5125);
DISPLAY INVISIBLE (-1975 5125);
FORCEPROP 1 LAST PATH I7
J 0
(-2050 5225);
DISPLAY 0.978723 (-2050 5225);
PAINT WHITE (-2050 5225);
DISPLAY INVISIBLE (-2050 5225);
FORCEPROP 2 LAST CDS_LIB pure_quanta
J 0
(-2000 5075);
DISPLAY INVISIBLE (-2000 5075);
FORCEADD P1V0..1
(-6400 1550);
FORCEPROP 3 LASTPIN (-6400 1500) SIG_NAME P3V3_STBY\g
J 0
(-6390 1510);
DISPLAY 0.659574 (-6390 1510);
PAINT MONO (-6390 1510);
DISPLAY INVISIBLE (-6390 1510);
FORCEPROP 1 LAST HDL_POWER P3V3_STBY
J 1
(-6400 1600);
DISPLAY 0.489362 (-6400 1600);
PAINT GREEN (-6400 1600);
FORCEPROP 2 LAST CDS_LIB pure_quanta_power
J 0
(-6400 1550);
DISPLAY INVISIBLE (-6400 1550);
FORCEPROP 1 LAST PATH I70
J 0
(-6350 1575);
DISPLAY 0.872340 (-6350 1575);
PAINT AQUA (-6350 1575);
DISPLAY INVISIBLE (-6350 1575);
FORCEADD Q_RES..1
(-6725 1300);
FORCEPROP 1 LAST $LOCATION R1105
J 0
(-6750 1325);
DISPLAY 0.404255 (-6750 1325);
PAINT SKYBLUE (-6750 1325);
FORCEPROP 0 LAST CDS_LOCATION R1105
J 0
(-6825 1400);
DISPLAY 0.680851 (-6825 1400);
DISPLAY INVISIBLE (-6825 1400);
FORCEPROP 0 LAST $SEC 1
J 0
(-6825 1400);
DISPLAY 0.680851 (-6825 1400);
PAINT MONO (-6825 1400);
DISPLAY INVISIBLE (-6825 1400);
FORCEPROP 0 LAST CDS_SEC 1
J 0
(-6825 1400);
DISPLAY 0.680851 (-6825 1400);
DISPLAY INVISIBLE (-6825 1400);
FORCEPROP 1 LASTPIN (-6825 1300) $PN 1
J 0
(-6813 1312);
DISPLAY 0.787234 (-6813 1312);
PAINT MONO (-6813 1312);
FORCEPROP 1 LASTPIN (-6625 1300) $PN 2
J 0
(-6663 1312);
DISPLAY 0.787234 (-6663 1312);
PAINT MONO (-6663 1312);
FORCEPROP 1 LAST MATERIAL CHIP
J 0
(-6625 1325);
DISPLAY 0.404255 (-6625 1325);
PAINT SKYBLUE (-6625 1325);
FORCEPROP 1 LAST VALUE 200
J 2
(-6800 1325);
DISPLAY 0.404255 (-6800 1325);
PAINT SKYBLUE (-6800 1325);
FORCEPROP 1 LAST PART_NUMBER CS12002FB06
J 0
(-6825 1375);
DISPLAY 0.404255 (-6825 1375);
PAINT SKYBLUE (-6825 1375);
FORCEPROP 2 LAST CDS_LIB pure_quanta
J 0
(-6725 1300);
DISPLAY INVISIBLE (-6725 1300);
FORCEPROP 1 LAST PATH I71
J 0
(-6775 1450);
DISPLAY 0.978723 (-6775 1450);
PAINT WHITE (-6775 1450);
DISPLAY INVISIBLE (-6775 1450);
FORCEPROP 1 LAST WATTAGE 1/16W
J 2
(-6750 1150);
DISPLAY 0.978723 (-6750 1150);
DISPLAY INVISIBLE (-6750 1150);
FORCEPROP 1 LAST TOLERANCE 1%
J 0
(-6725 1200);
DISPLAY 0.978723 (-6725 1200);
DISPLAY INVISIBLE (-6725 1200);
FORCEPROP 1 LAST PACK_TYPE 0402LF
J 0
(-6475 1150);
DISPLAY 0.978723 (-6475 1150);
DISPLAY INVISIBLE (-6475 1150);
FORCEADD Q_RES..1
(-6725 1125);
FORCEPROP 1 LAST $LOCATION R1106
J 0
(-6750 1150);
DISPLAY 0.404255 (-6750 1150);
PAINT SKYBLUE (-6750 1150);
FORCEPROP 0 LAST CDS_LOCATION R1106
J 0
(-6825 1225);
DISPLAY 0.680851 (-6825 1225);
DISPLAY INVISIBLE (-6825 1225);
FORCEPROP 0 LAST $SEC 1
J 0
(-6825 1225);
DISPLAY 0.680851 (-6825 1225);
PAINT MONO (-6825 1225);
DISPLAY INVISIBLE (-6825 1225);
FORCEPROP 0 LAST CDS_SEC 1
J 0
(-6825 1225);
DISPLAY 0.680851 (-6825 1225);
DISPLAY INVISIBLE (-6825 1225);
FORCEPROP 1 LASTPIN (-6825 1125) $PN 1
J 0
(-6813 1137);
DISPLAY 0.787234 (-6813 1137);
PAINT MONO (-6813 1137);
FORCEPROP 1 LASTPIN (-6625 1125) $PN 2
J 0
(-6663 1137);
DISPLAY 0.787234 (-6663 1137);
PAINT MONO (-6663 1137);
FORCEPROP 1 LAST MATERIAL CHIP
J 0
(-6625 1150);
DISPLAY 0.404255 (-6625 1150);
PAINT SKYBLUE (-6625 1150);
FORCEPROP 1 LAST PART_NUMBER CS12002FB06
J 0
(-6825 1200);
DISPLAY 0.404255 (-6825 1200);
PAINT SKYBLUE (-6825 1200);
FORCEPROP 1 LAST VALUE 200
J 2
(-6800 1150);
DISPLAY 0.404255 (-6800 1150);
PAINT SKYBLUE (-6800 1150);
FORCEPROP 2 LAST CDS_LIB pure_quanta
J 0
(-6725 1125);
DISPLAY INVISIBLE (-6725 1125);
FORCEPROP 1 LAST PATH I72
J 0
(-6775 1275);
DISPLAY 0.978723 (-6775 1275);
PAINT WHITE (-6775 1275);
DISPLAY INVISIBLE (-6775 1275);
FORCEPROP 1 LAST WATTAGE 1/16W
J 2
(-6750 975);
DISPLAY 0.978723 (-6750 975);
DISPLAY INVISIBLE (-6750 975);
FORCEPROP 1 LAST TOLERANCE 1%
J 0
(-6725 1025);
DISPLAY 0.978723 (-6725 1025);
DISPLAY INVISIBLE (-6725 1025);
FORCEPROP 1 LAST PACK_TYPE 0402LF
J 0
(-6475 975);
DISPLAY 0.978723 (-6475 975);
DISPLAY INVISIBLE (-6475 975);
FORCEADD Q_RES..1
(-6725 925);
FORCEPROP 1 LAST $LOCATION R1127
J 0
(-6750 950);
DISPLAY 0.404255 (-6750 950);
PAINT SKYBLUE (-6750 950);
FORCEPROP 0 LAST CDS_LOCATION R1127
J 0
(-6825 1025);
DISPLAY 0.680851 (-6825 1025);
DISPLAY INVISIBLE (-6825 1025);
FORCEPROP 0 LAST $SEC 1
J 0
(-6825 1025);
DISPLAY 0.680851 (-6825 1025);
PAINT MONO (-6825 1025);
DISPLAY INVISIBLE (-6825 1025);
FORCEPROP 0 LAST CDS_SEC 1
J 0
(-6825 1025);
DISPLAY 0.680851 (-6825 1025);
DISPLAY INVISIBLE (-6825 1025);
FORCEPROP 1 LASTPIN (-6825 925) $PN 1
J 0
(-6813 937);
DISPLAY 0.787234 (-6813 937);
PAINT MONO (-6813 937);
FORCEPROP 1 LASTPIN (-6625 925) $PN 2
J 0
(-6663 937);
DISPLAY 0.787234 (-6663 937);
PAINT MONO (-6663 937);
FORCEPROP 1 LAST MATERIAL CHIP
J 0
(-6625 950);
DISPLAY 0.404255 (-6625 950);
PAINT SKYBLUE (-6625 950);
FORCEPROP 1 LAST VALUE 200
J 2
(-6800 950);
DISPLAY 0.404255 (-6800 950);
PAINT SKYBLUE (-6800 950);
FORCEPROP 1 LAST PART_NUMBER CS12002FB06
J 0
(-6825 1000);
DISPLAY 0.404255 (-6825 1000);
PAINT SKYBLUE (-6825 1000);
FORCEPROP 2 LAST CDS_LIB pure_quanta
J 0
(-6725 925);
DISPLAY INVISIBLE (-6725 925);
FORCEPROP 1 LAST PATH I73
J 0
(-6775 1075);
DISPLAY 0.978723 (-6775 1075);
PAINT WHITE (-6775 1075);
DISPLAY INVISIBLE (-6775 1075);
FORCEPROP 1 LAST PACK_TYPE 0402LF
J 0
(-6475 775);
DISPLAY 0.978723 (-6475 775);
DISPLAY INVISIBLE (-6475 775);
FORCEPROP 1 LAST TOLERANCE 1%
J 0
(-6725 825);
DISPLAY 0.978723 (-6725 825);
DISPLAY INVISIBLE (-6725 825);
FORCEPROP 1 LAST WATTAGE 1/16W
J 2
(-6750 775);
DISPLAY 0.978723 (-6750 775);
DISPLAY INVISIBLE (-6750 775);
FORCEADD Q_RES..1
(-6725 725);
FORCEPROP 1 LAST $LOCATION R1128
J 0
(-6750 750);
DISPLAY 0.404255 (-6750 750);
PAINT SKYBLUE (-6750 750);
FORCEPROP 0 LAST CDS_LOCATION R1128
J 0
(-6825 825);
DISPLAY 0.680851 (-6825 825);
DISPLAY INVISIBLE (-6825 825);
FORCEPROP 0 LAST $SEC 1
J 0
(-6825 825);
DISPLAY 0.680851 (-6825 825);
PAINT MONO (-6825 825);
DISPLAY INVISIBLE (-6825 825);
FORCEPROP 0 LAST CDS_SEC 1
J 0
(-6825 825);
DISPLAY 0.680851 (-6825 825);
DISPLAY INVISIBLE (-6825 825);
FORCEPROP 1 LASTPIN (-6825 725) $PN 1
J 0
(-6813 737);
DISPLAY 0.787234 (-6813 737);
PAINT MONO (-6813 737);
FORCEPROP 1 LASTPIN (-6625 725) $PN 2
J 0
(-6663 737);
DISPLAY 0.787234 (-6663 737);
PAINT MONO (-6663 737);
FORCEPROP 1 LAST MATERIAL CHIP
J 0
(-6625 750);
DISPLAY 0.404255 (-6625 750);
PAINT SKYBLUE (-6625 750);
FORCEPROP 1 LAST PART_NUMBER CS12002FB06
J 0
(-6825 800);
DISPLAY 0.404255 (-6825 800);
PAINT SKYBLUE (-6825 800);
FORCEPROP 1 LAST VALUE 200
J 2
(-6800 750);
DISPLAY 0.404255 (-6800 750);
PAINT SKYBLUE (-6800 750);
FORCEPROP 2 LAST CDS_LIB pure_quanta
J 0
(-6725 725);
DISPLAY INVISIBLE (-6725 725);
FORCEPROP 1 LAST PATH I74
J 0
(-6775 875);
DISPLAY 0.978723 (-6775 875);
PAINT WHITE (-6775 875);
DISPLAY INVISIBLE (-6775 875);
FORCEPROP 1 LAST PACK_TYPE 0402LF
J 0
(-6475 575);
DISPLAY 0.978723 (-6475 575);
DISPLAY INVISIBLE (-6475 575);
FORCEPROP 1 LAST TOLERANCE 1%
J 0
(-6725 625);
DISPLAY 0.978723 (-6725 625);
DISPLAY INVISIBLE (-6725 625);
FORCEPROP 1 LAST WATTAGE 1/16W
J 2
(-6750 575);
DISPLAY 0.978723 (-6750 575);
DISPLAY INVISIBLE (-6750 575);
FORCEADD Q_LED..1
R 2
(-7400 1300);
FORCEPROP 1 LAST $LOCATION D12
J 2
(-7275 1350);
DISPLAY 0.468085 (-7275 1350);
PAINT SKYBLUE (-7275 1350);
FORCEPROP 0 LAST CDS_LOCATION D12
J 0
(-7400 1450);
DISPLAY 0.680851 (-7400 1450);
DISPLAY INVISIBLE (-7400 1450);
FORCEPROP 0 LAST $SEC 1
J 0
(-7400 1450);
DISPLAY 0.680851 (-7400 1450);
PAINT MONO (-7400 1450);
DISPLAY INVISIBLE (-7400 1450);
FORCEPROP 0 LAST CDS_SEC 1
J 0
(-7400 1450);
DISPLAY 0.680851 (-7400 1450);
DISPLAY INVISIBLE (-7400 1450);
FORCEPROP 0 LASTPIN (-7250 1300) $PN A
J 0
(-7240 1310);
DISPLAY 0.680851 (-7240 1310);
PAINT MONO (-7240 1310);
FORCEPROP 0 LASTPIN (-7550 1300) $PN C
J 2
(-7560 1310);
DISPLAY 0.680851 (-7560 1310);
PAINT MONO (-7560 1310);
FORCEPROP 1 LAST PART_NUMBER BEGR0278Z00
J 2
(-7375 1375);
DISPLAY 0.382979 (-7375 1375);
PAINT SKYBLUE (-7375 1375);
FORCEPROP 1 LAST MATERIAL IC
J 2
(-7300 1380);
DISPLAY 0.468085 (-7300 1380);
PAINT SKYBLUE (-7300 1380);
FORCEPROP 0 LAST MANUF_PN 19-213/GVC-AMNB/3T
J 2
(-7300 1575);
DISPLAY 0.680851 (-7300 1575);
DISPLAY INVISIBLE (-7300 1575);
FORCEPROP 0 LAST COLOR LED_GREEN
J 2
(-7300 1625);
DISPLAY 0.680851 (-7300 1625);
DISPLAY INVISIBLE (-7300 1625);
FORCEPROP 0 LAST PACK_TYPE SMLF
J 2
(-7400 1400);
DISPLAY 0.680851 (-7400 1400);
DISPLAY INVISIBLE (-7400 1400);
FORCEPROP 1 LAST NEEDS_NO_SIZE TRUE
J 2
(-7400 1300);
DISPLAY 0.468085 (-7400 1300);
PAINT GREEN (-7400 1300);
DISPLAY INVISIBLE (-7400 1300);
FORCEPROP 1 LAST PATH I75
J 2
(-7525 1380);
DISPLAY 0.723404 (-7525 1380);
PAINT GREEN (-7525 1380);
DISPLAY INVISIBLE (-7525 1380);
FORCEPROP 2 LAST CDS_LIB pure_quanta
J 0
(-7400 1300);
DISPLAY INVISIBLE (-7400 1300);
FORCEADD Q_LED..1
R 2
(-7400 1125);
FORCEPROP 1 LAST $LOCATION D13
J 2
(-7275 1150);
DISPLAY 0.468085 (-7275 1150);
PAINT SKYBLUE (-7275 1150);
FORCEPROP 0 LAST CDS_LOCATION D13
J 0
(-7400 1275);
DISPLAY 0.680851 (-7400 1275);
DISPLAY INVISIBLE (-7400 1275);
FORCEPROP 0 LAST $SEC 1
J 0
(-7400 1275);
DISPLAY 0.680851 (-7400 1275);
PAINT MONO (-7400 1275);
DISPLAY INVISIBLE (-7400 1275);
FORCEPROP 0 LAST CDS_SEC 1
J 0
(-7400 1275);
DISPLAY 0.680851 (-7400 1275);
DISPLAY INVISIBLE (-7400 1275);
FORCEPROP 0 LASTPIN (-7250 1125) $PN A
J 0
(-7240 1135);
DISPLAY 0.680851 (-7240 1135);
PAINT MONO (-7240 1135);
FORCEPROP 0 LASTPIN (-7550 1125) $PN C
J 2
(-7560 1135);
DISPLAY 0.680851 (-7560 1135);
PAINT MONO (-7560 1135);
FORCEPROP 1 LAST PART_NUMBER BEGR0278Z00
J 2
(-7375 1200);
DISPLAY 0.382979 (-7375 1200);
PAINT SKYBLUE (-7375 1200);
FORCEPROP 1 LAST MATERIAL IC
J 2
(-7300 1205);
DISPLAY 0.468085 (-7300 1205);
PAINT SKYBLUE (-7300 1205);
FORCEPROP 0 LAST MANUF_PN 19-213/GVC-AMNB/3T
J 2
(-7300 1400);
DISPLAY 0.680851 (-7300 1400);
DISPLAY INVISIBLE (-7300 1400);
FORCEPROP 0 LAST COLOR LED_GREEN
J 2
(-7300 1450);
DISPLAY 0.680851 (-7300 1450);
DISPLAY INVISIBLE (-7300 1450);
FORCEPROP 0 LAST PACK_TYPE SMLF
J 2
(-7400 1225);
DISPLAY 0.680851 (-7400 1225);
DISPLAY INVISIBLE (-7400 1225);
FORCEPROP 1 LAST NEEDS_NO_SIZE TRUE
J 2
(-7400 1125);
DISPLAY 0.468085 (-7400 1125);
PAINT GREEN (-7400 1125);
DISPLAY INVISIBLE (-7400 1125);
FORCEPROP 1 LAST PATH I76
J 2
(-7525 1205);
DISPLAY 0.723404 (-7525 1205);
PAINT GREEN (-7525 1205);
DISPLAY INVISIBLE (-7525 1205);
FORCEPROP 2 LAST CDS_LIB pure_quanta
J 0
(-7400 1125);
DISPLAY INVISIBLE (-7400 1125);
FORCEADD Q_LED..1
R 2
(-7400 725);
FORCEPROP 1 LAST $LOCATION D33
J 2
(-7275 775);
DISPLAY 0.468085 (-7275 775);
PAINT SKYBLUE (-7275 775);
FORCEPROP 0 LAST CDS_LOCATION D33
J 0
(-7400 875);
DISPLAY 0.680851 (-7400 875);
DISPLAY INVISIBLE (-7400 875);
FORCEPROP 0 LAST $SEC 1
J 0
(-7400 875);
DISPLAY 0.680851 (-7400 875);
PAINT MONO (-7400 875);
DISPLAY INVISIBLE (-7400 875);
FORCEPROP 0 LAST CDS_SEC 1
J 0
(-7400 875);
DISPLAY 0.680851 (-7400 875);
DISPLAY INVISIBLE (-7400 875);
FORCEPROP 0 LASTPIN (-7250 725) $PN A
J 0
(-7240 735);
DISPLAY 0.680851 (-7240 735);
PAINT MONO (-7240 735);
FORCEPROP 0 LASTPIN (-7550 725) $PN C
J 2
(-7560 735);
DISPLAY 0.680851 (-7560 735);
PAINT MONO (-7560 735);
FORCEPROP 1 LAST PART_NUMBER BEGR0278Z00
J 2
(-7375 800);
DISPLAY 0.382979 (-7375 800);
PAINT SKYBLUE (-7375 800);
FORCEPROP 1 LAST MATERIAL IC
J 2
(-7300 805);
DISPLAY 0.468085 (-7300 805);
PAINT SKYBLUE (-7300 805);
FORCEPROP 0 LAST MANUF_PN 19-213/GVC-AMNB/3T
J 2
(-7300 1000);
DISPLAY 0.680851 (-7300 1000);
DISPLAY INVISIBLE (-7300 1000);
FORCEPROP 0 LAST COLOR LED_GREEN
J 2
(-7300 1050);
DISPLAY 0.680851 (-7300 1050);
DISPLAY INVISIBLE (-7300 1050);
FORCEPROP 0 LAST PACK_TYPE SMLF
J 2
(-7400 825);
DISPLAY 0.680851 (-7400 825);
DISPLAY INVISIBLE (-7400 825);
FORCEPROP 1 LAST NEEDS_NO_SIZE TRUE
J 2
(-7400 725);
DISPLAY 0.468085 (-7400 725);
PAINT GREEN (-7400 725);
DISPLAY INVISIBLE (-7400 725);
FORCEPROP 1 LAST PATH I77
J 2
(-7525 805);
DISPLAY 0.723404 (-7525 805);
PAINT GREEN (-7525 805);
DISPLAY INVISIBLE (-7525 805);
FORCEPROP 2 LAST CDS_LIB pure_quanta
J 0
(-7400 725);
DISPLAY INVISIBLE (-7400 725);
FORCEADD UNIVERSAL_GND..1
(-8050 300);
FORCEPROP 3 LASTPIN (-8050 350) SIG_NAME GND\g
J 0
(-8040 360);
DISPLAY 0.659574 (-8040 360);
PAINT MONO (-8040 360);
DISPLAY INVISIBLE (-8040 360);
FORCEPROP 2 LAST CDS_LIB pure_quanta_power
J 0
(-8050 300);
DISPLAY INVISIBLE (-8050 300);
FORCEPROP 1 LAST PATH I78
J 0
(-7975 300);
DISPLAY 0.872340 (-7975 300);
PAINT AQUA (-7975 300);
DISPLAY INVISIBLE (-7975 300);
FORCEPROP 2 LAST BOM_COST OCP3.0 
J 0
(-8250 375);
DISPLAY 0.680851 (-8250 375);
DISPLAY INVISIBLE (-8250 375);
FORCEPROP 1 LAST HDL_POWER GND
J 1
(-8025 225);
DISPLAY 0.872340 (-8025 225);
PAINT GREEN (-8025 225);
DISPLAY INVISIBLE (-8025 225);
FORCEADD MOSFET_DUAL_6P..1
R 6
(-8525 1125);
FORCEPROP 1 LAST $LOCATION Q34
J 0
(-8525 1250);
DISPLAY 0.468085 (-8525 1250);
PAINT SKYBLUE (-8525 1250);
FORCEPROP 0 LAST CDS_LOCATION Q34
J 0
(-8650 1425);
DISPLAY 0.680851 (-8650 1425);
DISPLAY INVISIBLE (-8650 1425);
FORCEPROP 0 LAST $SEC 1
J 0
(-8650 1425);
DISPLAY 0.680851 (-8650 1425);
PAINT MONO (-8650 1425);
DISPLAY INVISIBLE (-8650 1425);
FORCEPROP 0 LAST CDS_SEC 1
J 0
(-8650 1425);
DISPLAY 0.680851 (-8650 1425);
DISPLAY INVISIBLE (-8650 1425);
FORCEPROP 0 LASTPIN (-8825 1175) $PN 6
J 2
(-8835 1185);
DISPLAY 0.680851 (-8835 1185);
PAINT MONO (-8835 1185);
FORCEPROP 0 LASTPIN (-8225 1175) $PN 3
J 0
(-8215 1185);
DISPLAY 0.680851 (-8215 1185);
PAINT MONO (-8215 1185);
FORCEPROP 0 LASTPIN (-8825 1125) $PN 2
J 2
(-8835 1135);
DISPLAY 0.680851 (-8835 1135);
PAINT MONO (-8835 1135);
FORCEPROP 0 LASTPIN (-8225 1125) $PN 5
J 0
(-8215 1135);
DISPLAY 0.680851 (-8215 1135);
PAINT MONO (-8215 1135);
FORCEPROP 0 LASTPIN (-8825 1075) $PN 1
J 2
(-8835 1085);
DISPLAY 0.680851 (-8835 1085);
PAINT MONO (-8835 1085);
FORCEPROP 0 LASTPIN (-8225 1075) $PN 4
J 0
(-8215 1085);
DISPLAY 0.680851 (-8215 1085);
PAINT MONO (-8215 1085);
FORCEPROP 1 LAST MATERIAL IC
J 0
(-8650 1250);
DISPLAY 0.468085 (-8650 1250);
PAINT SKYBLUE (-8650 1250);
FORCEPROP 1 LAST PART_NUMBER BAM70020047
J 0
(-8650 1325);
DISPLAY 0.468085 (-8650 1325);
PAINT SKYBLUE (-8650 1325);
FORCEPROP 2 LAST CDS_LIB pure_quanta
J 0
(-8525 1125);
DISPLAY INVISIBLE (-8525 1125);
FORCEPROP 1 LAST PATH I79
J 0
(-8525 1125);
DISPLAY 0.723404 (-8525 1125);
PAINT GREEN (-8525 1125);
DISPLAY INVISIBLE (-8525 1125);
FORCEPROP 1 LAST CDS_LMAN_SYM_OUTLINE -150,100,150,-100
J 0
(-8525 1125);
DISPLAY 0.468085 (-8525 1125);
PAINT GREEN (-8525 1125);
DISPLAY INVISIBLE (-8525 1125);
FORCEPROP 1 LAST NEEDS_NO_SIZE TRUE
J 0
(-8525 1104);
DISPLAY 0.468085 (-8525 1104);
PAINT GREEN (-8525 1104);
DISPLAY INVISIBLE (-8525 1104);
FORCEPROP 0 LAST VALUE 2N7002KDW
J 0
(-8650 843);
DISPLAY 0.680851 (-8650 843);
DISPLAY INVISIBLE (-8650 843);
FORCEPROP 0 LAST PART_TYPE SMLF
J 0
(-8650 1375);
DISPLAY 0.680851 (-8650 1375);
DISPLAY INVISIBLE (-8650 1375);
FORCEADD Q_LED..1
R 2
(-2950 5075);
FORCEPROP 1 LAST LOCATION D5
J 2
(-2850 5260);
DISPLAY 0.489362 (-2850 5260);
PAINT SKYBLUE (-2850 5260);
FORCEPROP 0 LAST $SEC 1
J 0
(-2850 5300);
DISPLAY 0.680851 (-2850 5300);
PAINT MONO (-2850 5300);
DISPLAY INVISIBLE (-2850 5300);
FORCEPROP 0 LAST CDS_SEC 1
J 0
(-2850 5300);
DISPLAY 0.680851 (-2850 5300);
DISPLAY INVISIBLE (-2850 5300);
FORCEPROP 0 LASTPIN (-2800 5075) $PN A
J 0
(-2790 5085);
DISPLAY 0.489362 (-2790 5085);
PAINT MONO (-2790 5085);
FORCEPROP 0 LASTPIN (-3100 5075) $PN C
J 2
(-3110 5085);
DISPLAY 0.489362 (-3110 5085);
PAINT MONO (-3110 5085);
FORCEPROP 2 LAST PACK_TYPE SMLF
J 2
(-2775 4975);
DISPLAY 0.489362 (-2775 4975);
PAINT SKYBLUE (-2775 4975);
FORCEPROP 2 LAST COLOR LED_GREEN
J 2
(-2775 4875);
DISPLAY 0.489362 (-2775 4875);
FORCEPROP 1 LAST PART_NUMBER BEGR0278Z00
J 2
(-2850 5210);
DISPLAY 0.489362 (-2850 5210);
PAINT SKYBLUE (-2850 5210);
FORCEPROP 1 LAST MATERIAL IC
J 2
(-2850 5155);
DISPLAY 0.489362 (-2850 5155);
PAINT SKYBLUE (-2850 5155);
FORCEPROP 2 LAST MANUF_PN 19-213/GVC-AMNB/3T
J 2
(-2775 4925);
DISPLAY 0.680851 (-2775 4925);
FORCEPROP 1 LAST PATH I8
J 2
(-3075 5155);
DISPLAY 0.723404 (-3075 5155);
PAINT GREEN (-3075 5155);
DISPLAY INVISIBLE (-3075 5155);
FORCEPROP 1 LAST NEEDS_NO_SIZE TRUE
J 2
(-2950 5075);
DISPLAY 0.468085 (-2950 5075);
PAINT GREEN (-2950 5075);
DISPLAY INVISIBLE (-2950 5075);
FORCEPROP 2 LAST CDS_LIB pure_quanta
J 2
(-2950 5075);
DISPLAY INVISIBLE (-2950 5075);
FORCEADD UNIVERSAL_GND..1
(-8925 950);
FORCEPROP 3 LASTPIN (-8925 1000) SIG_NAME GND\g
J 0
(-8915 1010);
DISPLAY 0.659574 (-8915 1010);
PAINT MONO (-8915 1010);
DISPLAY INVISIBLE (-8915 1010);
FORCEPROP 2 LAST CDS_LIB pure_quanta_power
J 0
(-8925 950);
DISPLAY INVISIBLE (-8925 950);
FORCEPROP 1 LAST PATH I80
J 0
(-8850 950);
DISPLAY 0.872340 (-8850 950);
PAINT AQUA (-8850 950);
DISPLAY INVISIBLE (-8850 950);
FORCEPROP 2 LAST BOM_COST OCP3.0 
J 0
(-9125 1025);
DISPLAY 0.680851 (-9125 1025);
DISPLAY INVISIBLE (-9125 1025);
FORCEPROP 1 LAST HDL_POWER GND
J 1
(-8900 875);
DISPLAY 0.872340 (-8900 875);
PAINT GREEN (-8900 875);
DISPLAY INVISIBLE (-8900 875);
FORCEADD OFFPAGE..1
(-9325 1125);
FORCEPROP 2 LAST $XR0 80 
J 0
(-9576 1125);
DISPLAY 0.638298 (-9576 1125);
PAINT MONO (-9576 1125);
FORCEPROP 2 LAST CDS_LIB standard
J 0
(-9325 1125);
DISPLAY INVISIBLE (-9325 1125);
FORCEPROP 2 LAST PATH I81
J 0
(-9275 1200);
DISPLAY 0.680851 (-9275 1200);
DISPLAY INVISIBLE (-9275 1200);
FORCEPROP 1 LAST COMMENT_BODY TRUE
J 0
(-9200 1025);
DISPLAY 0.872340 (-9200 1025);
PAINT GREEN (-9200 1025);
DISPLAY INVISIBLE (-9200 1025);
FORCEPROP 1 LAST OFFPAGE TRUE
J 0
(-9000 1000);
DISPLAY 0.872340 (-9000 1000);
PAINT GREEN (-9000 1000);
DISPLAY INVISIBLE (-9000 1000);
FORCEADD OFFPAGE..1
(-9325 875);
FORCEPROP 2 LAST $XR0 80 
J 0
(-9576 875);
DISPLAY 0.638298 (-9576 875);
PAINT MONO (-9576 875);
FORCEPROP 2 LAST CDS_LIB standard
J 0
(-9325 875);
DISPLAY INVISIBLE (-9325 875);
FORCEPROP 2 LAST PATH I82
J 0
(-9275 950);
DISPLAY 0.680851 (-9275 950);
DISPLAY INVISIBLE (-9275 950);
FORCEPROP 1 LAST OFFPAGE TRUE
J 0
(-9000 750);
DISPLAY 0.872340 (-9000 750);
PAINT GREEN (-9000 750);
DISPLAY INVISIBLE (-9000 750);
FORCEPROP 1 LAST COMMENT_BODY TRUE
J 0
(-9200 775);
DISPLAY 0.872340 (-9200 775);
PAINT GREEN (-9200 775);
DISPLAY INVISIBLE (-9200 775);
FORCEADD OFFPAGE..1
(-9325 675);
FORCEPROP 2 LAST $XR0 80 
J 0
(-9576 675);
DISPLAY 0.638298 (-9576 675);
PAINT MONO (-9576 675);
FORCEPROP 2 LAST CDS_LIB standard
J 0
(-9325 675);
DISPLAY INVISIBLE (-9325 675);
FORCEPROP 2 LAST PATH I83
J 0
(-9275 750);
DISPLAY 0.680851 (-9275 750);
DISPLAY INVISIBLE (-9275 750);
FORCEPROP 1 LAST COMMENT_BODY TRUE
J 0
(-9200 575);
DISPLAY 0.872340 (-9200 575);
PAINT GREEN (-9200 575);
DISPLAY INVISIBLE (-9200 575);
FORCEPROP 1 LAST OFFPAGE TRUE
J 0
(-9000 550);
DISPLAY 0.872340 (-9000 550);
PAINT GREEN (-9000 550);
DISPLAY INVISIBLE (-9000 550);
FORCEADD UNIVERSAL_GND..1
(-8900 475);
FORCEPROP 3 LASTPIN (-8900 525) SIG_NAME GND\g
J 0
(-8890 535);
DISPLAY 0.659574 (-8890 535);
PAINT MONO (-8890 535);
DISPLAY INVISIBLE (-8890 535);
FORCEPROP 2 LAST CDS_LIB pure_quanta_power
J 0
(-8900 475);
DISPLAY INVISIBLE (-8900 475);
FORCEPROP 1 LAST PATH I84
J 0
(-8825 475);
DISPLAY 0.872340 (-8825 475);
PAINT AQUA (-8825 475);
DISPLAY INVISIBLE (-8825 475);
FORCEPROP 2 LAST BOM_COST OCP3.0 
J 0
(-9100 550);
DISPLAY 0.680851 (-9100 550);
DISPLAY INVISIBLE (-9100 550);
FORCEPROP 1 LAST HDL_POWER GND
J 1
(-8875 400);
DISPLAY 0.872340 (-8875 400);
PAINT GREEN (-8875 400);
DISPLAY INVISIBLE (-8875 400);
FORCEADD OFFPAGE..1
(-9325 425);
FORCEPROP 2 LAST $XR0 80 
J 0
(-9576 425);
DISPLAY 0.638298 (-9576 425);
PAINT MONO (-9576 425);
FORCEPROP 2 LAST CDS_LIB standard
J 0
(-9325 425);
DISPLAY INVISIBLE (-9325 425);
FORCEPROP 2 LAST PATH I85
J 0
(-9275 500);
DISPLAY 0.680851 (-9275 500);
DISPLAY INVISIBLE (-9275 500);
FORCEPROP 1 LAST OFFPAGE TRUE
J 0
(-9000 300);
DISPLAY 0.872340 (-9000 300);
PAINT GREEN (-9000 300);
DISPLAY INVISIBLE (-9000 300);
FORCEPROP 1 LAST COMMENT_BODY TRUE
J 0
(-9200 325);
DISPLAY 0.872340 (-9200 325);
PAINT GREEN (-9200 325);
DISPLAY INVISIBLE (-9200 325);
FORCEADD Q_LED..1
R 2
(-3100 3450);
FORCEPROP 1 LAST LOCATION D6
J 0
(-3200 3635);
DISPLAY 0.489362 (-3200 3635);
PAINT SKYBLUE (-3200 3635);
FORCEPROP 0 LAST $SEC 1
J 0
(-3200 3800);
DISPLAY 0.680851 (-3200 3800);
PAINT MONO (-3200 3800);
DISPLAY INVISIBLE (-3200 3800);
FORCEPROP 0 LAST CDS_SEC 1
J 0
(-3000 3825);
DISPLAY 0.680851 (-3000 3825);
DISPLAY INVISIBLE (-3000 3825);
FORCEPROP 0 LASTPIN (-2950 3450) $PN A
J 0
(-2940 3460);
DISPLAY 0.489362 (-2940 3460);
PAINT MONO (-2940 3460);
FORCEPROP 0 LASTPIN (-3250 3450) $PN C
J 2
(-3260 3460);
DISPLAY 0.489362 (-3260 3460);
PAINT MONO (-3260 3460);
FORCEPROP 2 LAST PACK_TYPE SMLF
J 0
(-3200 3675);
DISPLAY 0.489362 (-3200 3675);
PAINT SKYBLUE (-3200 3675);
FORCEPROP 2 LAST COLOR LED_RED
J 0
(-3200 3775);
DISPLAY 0.489362 (-3200 3775);
FORCEPROP 1 LAST PART_NUMBER BERD0021Z02
J 0
(-3200 3585);
DISPLAY 0.489362 (-3200 3585);
PAINT SKYBLUE (-3200 3585);
FORCEPROP 1 LAST MATERIAL IC
J 0
(-3200 3530);
DISPLAY 0.489362 (-3200 3530);
PAINT SKYBLUE (-3200 3530);
FORCEPROP 2 LAST MANUF_PN LTST-C190KRKT
J 0
(-3200 3725);
DISPLAY 0.680851 (-3200 3725);
FORCEPROP 1 LAST PATH I9
J 2
(-3225 3530);
DISPLAY 0.723404 (-3225 3530);
PAINT GREEN (-3225 3530);
DISPLAY INVISIBLE (-3225 3530);
FORCEPROP 1 LAST NEEDS_NO_SIZE TRUE
J 2
(-3100 3450);
DISPLAY 0.468085 (-3100 3450);
PAINT GREEN (-3100 3450);
DISPLAY INVISIBLE (-3100 3450);
FORCEPROP 2 LAST CDS_LIB pure_quanta
J 0
(-3100 3450);
DISPLAY INVISIBLE (-3100 3450);
FORCEADD DNS..2
(-7925 4900);
PAINT RED (-7925 4900);
FORCEPROP 1 LAST COMMENT_BODY TRUE
R 1
J 0
(-7850 4675);
DISPLAY 0.872340 (-7850 4675);
PAINT GREEN (-7850 4675);
DISPLAY INVISIBLE (-7850 4675);
FORCEPROP 2 LAST CDS_LIB mstr_misc
J 0
(-7925 4900);
DISPLAY INVISIBLE (-7925 4900);
FORCEADD QUANTA_TITLE_BLOCK_C..1
(-375 -275);
FORCEPROP 0 LAST CDS_CON_LAST_MODIFIED Fri Mar 11 14:53:15 2022
J 0
(-2260 -260);
DISPLAY INVISIBLE (-2260 -260);
FORCEPROP 1 LAST CUSTOM_TXT_CDS <CON_LAST_MODIFIED>
J 0
(-2260 -260);
DISPLAY 0.978723 (-2260 -260);
FORCEPROP 2 LAST CUSTOM_TXT_CDS <XR_PAGE_TITLE>
J 0
(-8265 4975);
DISPLAY 0.638298 (-8265 4975);
PAINT PINK (-8265 4975);
DISPLAY INVISIBLE (-8265 4975);
FORCEPROP 1 LAST CUSTOM_TXT_CDS <NAME_2>
J 0
(-3550 -225);
FORCEPROP 1 LAST CUSTOM_TXT_CDS <NAME_1>
J 0
(-3550 -100);
FORCEPROP 1 LAST CUSTOM_TXT_CDS <Q_NUMBER>
J 0
(-1778 -172);
DISPLAY 1.212766 (-1778 -172);
FORCEPROP 1 LAST CUSTOM_TXT_CDS <Q_PROJ>
J 0
(-2757 -173);
DISPLAY 1.212766 (-2757 -173);
FORCEPROP 1 LAST CUSTOM_TXT_CDS <Q_REV>
J 0
(-559 -172);
DISPLAY 1.212766 (-559 -172);
FORCEPROP 1 LAST CUSTOM_TXT_CDS <CON_PAGE_NUM> OF <CON_TOTAL_PAGES>
J 0
(-821 -257);
DISPLAY 0.978723 (-821 -257);
FORCEPROP 1 LAST Q_DEPT BU9
J 1
(-4138 -226);
DISPLAY 1.957447 (-4138 -226);
PAINT GREEN (-4138 -226);
FORCEPROP 1 LAST Q_TITLE LED (2/2)
J 0
(-9675 -225);
DISPLAY 2.446809 (-9675 -225);
PAINT GREEN (-9675 -225);
FORCEPROP 1 LAST COMMENT_BODY TRUE
J 0
(-363 -288);
DISPLAY 0.978723 (-363 -288);
PAINT GREEN (-363 -288);
DISPLAY INVISIBLE (-363 -288);
FORCEPROP 2 LAST CDS_LIB pure_quanta
J 0
(-375 -275);
DISPLAY INVISIBLE (-375 -275);
FORCEPROP 1 LAST CDS_LMAN_SYM_OUTLINE -9475,6775,100,-125
J 0
(-375 -275);
DISPLAY 0.468085 (-375 -275);
PAINT GREEN (-375 -275);
DISPLAY INVISIBLE (-375 -275);
FORCEPROP 2 LAST PAGE_BORDER TRUE
J 0
(-8265 4975);
DISPLAY 0.638298 (-8265 4975);
PAINT PINK (-8265 4975);
DISPLAY INVISIBLE (-8265 4975);
FORCEPROP 2 LAST CDS_XR_PAGE_TITLE CR-143 : @T6G_MB_LIB.T6G(SCH_1):PAGE143
J 0
(-8265 4975);
DISPLAY 0.638298 (-8265 4975);
PAINT PINK (-8265 4975);
DISPLAY INVISIBLE (-8265 4975);
WIRE 16 -1 (-4100 3900)(-4100 4100);
WIRE 16 -1 (-4200 3550)(-4250 3550);
WIRE 16 -1 (-4700 5175)(-4725 5175);
WIRE 16 -1 (-4950 5525)(-4950 5725);
WIRE 16 -1 (-5100 3900)(-5100 4100);
WIRE 16 -1 (-4850 3550)(-4875 3550);
WIRE 16 -1 (-7200 5300)(-7200 5350);
WIRE 16 -1 (-6850 5025)(-6850 4900);
WIRE 16 -1 (-6775 5025)(-6850 5025);
WIRE 16 -1 (-7350 3675)(-7350 3725);
WIRE 16 -1 (-6925 3400)(-7000 3400);
WIRE 16 -1 (-7000 3400)(-7000 3275);
WIRE 16 -1 (-4750 550)(-4425 550);
WIRE 16 -1 (-4750 550)(-4750 425);
WIRE 16 -1 (-3950 5525)(-3950 5725);
WIRE 16 -1 (-2725 550)(-2725 925);
WIRE 16 -1 (-2725 550)(-3175 550);
WIRE 16 -1 (-2550 1975)(-2550 2350);
WIRE 16 -1 (-2550 1975)(-3025 1975);
WIRE 16 -1 (-4850 1475)(-4850 1350);
WIRE 16 -1 (-4050 5175)(-4100 5175);
WIRE 16 -1 (-8850 2600)(-8950 2600);
WIRE 16 -1 (-8950 2600)(-8950 2525);
WIRE 16 -1 (-8925 2150)(-8925 2050);
WIRE 16 -1 (-8825 2150)(-8925 2150);
WIRE 16 -1 (-8825 1075)(-8925 1075);
WIRE 16 -1 (-8925 1075)(-8925 1000);
WIRE 16 -1 (-8900 625)(-8900 525);
WIRE 16 -1 (-8800 625)(-8900 625);
WIRE 16 -1 (-1875 5675)(-1875 5075);
WIRE 16 -1 (-1875 5075)(-1900 5075);
WIRE 16 -1 (-2125 4050)(-2125 3450);
WIRE 16 -1 (-2125 3450)(-2150 3450);
WIRE 16 -1 (-7350 4075)(-7350 3975);
WIRE 16 -1 (-7350 3975)(-7000 3975);
WIRE 16 -1 (-7350 3975)(-7350 3925);
WIRE 16 -1 (-7000 3975)(-7000 3600);
WIRE 16 -1 (-7000 3600)(-6925 3600);
WIRE 16 -1 (-7200 5600)(-6850 5600);
WIRE 16 -1 (-7200 5700)(-7200 5600);
WIRE 16 -1 (-7200 5600)(-7200 5550);
WIRE 16 -1 (-6850 5600)(-6850 5225);
WIRE 16 -1 (-6850 5225)(-6775 5225);
WIRE 16 -1 (-6425 2450)(-6425 2250);
WIRE 16 -1 (-6425 2650)(-6425 2450);
WIRE 16 -1 (-6425 2450)(-6650 2450);
WIRE 16 -1 (-6425 2250)(-6650 2250);
WIRE 16 -1 (-6425 2825)(-6425 2650);
WIRE 16 -1 (-6425 2650)(-6650 2650);
WIRE 16 -1 (-6425 2825)(-6425 3025);
WIRE 16 -1 (-6650 2825)(-6425 2825);
WIRE 16 -1 (-8075 2600)(-8075 2150);
WIRE 16 -1 (-8250 2600)(-8075 2600);
WIRE 16 -1 (-8075 2150)(-8075 1875);
WIRE 16 -1 (-8225 2150)(-8075 2150);
WIRE 16 -1 (-6400 1300)(-6400 1500);
WIRE 16 -1 (-6625 1300)(-6400 1300);
WIRE 16 -1 (-6400 1300)(-6400 1125);
WIRE 16 -1 (-6400 1125)(-6625 1125);
WIRE 16 -1 (-6400 1125)(-6400 925);
WIRE 16 -1 (-6400 925)(-6625 925);
WIRE 16 -1 (-6400 925)(-6400 725);
WIRE 16 -1 (-6400 725)(-6625 725);
WIRE 16 -1 (-8050 1075)(-8050 625);
WIRE 16 -1 (-8225 1075)(-8050 1075);
WIRE 16 -1 (-8050 625)(-8050 350);
WIRE 16 -1 (-8200 625)(-8050 625);
WIRE 16 -1 (-8925 1300)(-7550 1300);
FORCEPROP 2 LAST SIG_NAME LED_D4
J 0
(-7910 1335);
DISPLAY 0.553191 (-7910 1335);
FORCEPROP 2 LASTPROP $XRERR UNIQUE?
J 0
(-8150 1335);
DISPLAY 0.638298 (-8150 1335);
PAINT MONO (-8150 1335);
DISPLAY INVISIBLE (-8150 1335);
WIRE 16 -1 (-8925 1175)(-8925 1300);
WIRE 16 -1 (-8825 1175)(-8925 1175);
WIRE 16 -1 (-9275 875)(-8100 875);
FORCEPROP 2 LAST SIG_NAME FM_LED_D5
J 0
(-9310 935);
DISPLAY 0.553191 (-9310 935);
WIRE 16 -1 (-8100 1125)(-8100 875);
WIRE 16 -1 (-8225 1125)(-8100 1125);
WIRE 16 -1 (-8925 825)(-8925 725);
WIRE 16 -1 (-7950 825)(-8925 825);
WIRE 16 -1 (-8925 725)(-8800 725);
WIRE 16 -1 (-7950 925)(-7950 825);
WIRE 16 -1 (-7550 925)(-7950 925);
FORCEPROP 2 LAST SIG_NAME LED_D6
J 0
(-7910 960);
DISPLAY 0.553191 (-7910 960);
FORCEPROP 2 LASTPROP $XRERR UNIQUE?
J 0
(-8150 960);
DISPLAY 0.638298 (-8150 960);
PAINT MONO (-8150 960);
DISPLAY INVISIBLE (-8150 960);
WIRE 16 -1 (-8200 725)(-7550 725);
FORCEPROP 2 LAST SIG_NAME LED_D7
J 0
(-7910 760);
DISPLAY 0.553191 (-7910 760);
FORCEPROP 2 LASTPROP $XRERR UNIQUE?
J 0
(-8150 760);
DISPLAY 0.638298 (-8150 760);
PAINT MONO (-8150 760);
DISPLAY INVISIBLE (-8150 760);
WIRE 16 -1 (-7250 925)(-6825 925);
FORCEPROP 2 LAST SIG_NAME LED_D6_R
J 0
(-7185 960);
DISPLAY 0.553191 (-7185 960);
FORCEPROP 2 LASTPROP $XRERR UNIQUE?
J 0
(-7425 960);
DISPLAY 0.638298 (-7425 960);
PAINT MONO (-7425 960);
DISPLAY INVISIBLE (-7425 960);
WIRE 16 -1 (-7950 1125)(-7950 1175);
WIRE 16 -1 (-7550 1125)(-7950 1125);
FORCEPROP 2 LAST SIG_NAME LED_D5
J 0
(-7910 1160);
DISPLAY 0.553191 (-7910 1160);
FORCEPROP 2 LASTPROP $XRERR UNIQUE?
J 0
(-8150 1160);
DISPLAY 0.638298 (-8150 1160);
PAINT MONO (-8150 1160);
DISPLAY INVISIBLE (-8150 1160);
WIRE 16 -1 (-7950 1175)(-8225 1175);
WIRE 16 -1 (-7275 2825)(-6850 2825);
WIRE 16 -1 (-7275 2650)(-6850 2650);
FORCEPROP 2 LAST SIG_NAME LED_D1_R
J 0
(-7210 2685);
DISPLAY 0.553191 (-7210 2685);
FORCEPROP 2 LASTPROP $XRERR UNIQUE?
J 0
(-7450 2685);
DISPLAY 0.638298 (-7450 2685);
PAINT MONO (-7450 2685);
DISPLAY INVISIBLE (-7450 2685);
WIRE 16 -1 (-8950 2825)(-7575 2825);
FORCEPROP 2 LAST SIG_NAME LED_D0
J 0
(-7935 2860);
DISPLAY 0.553191 (-7935 2860);
FORCEPROP 2 LASTPROP $XRERR UNIQUE?
J 0
(-8175 2860);
DISPLAY 0.638298 (-8175 2860);
PAINT MONO (-8175 2860);
DISPLAY INVISIBLE (-8175 2860);
WIRE 16 -1 (-8950 2700)(-8950 2825);
WIRE 16 -1 (-8850 2700)(-8950 2700);
WIRE 16 -1 (-7250 725)(-6825 725);
FORCEPROP 2 LAST SIG_NAME LED_D7_R
J 0
(-7185 760);
DISPLAY 0.553191 (-7185 760);
FORCEPROP 2 LASTPROP $XRERR UNIQUE?
J 0
(-7425 760);
DISPLAY 0.638298 (-7425 760);
PAINT MONO (-7425 760);
DISPLAY INVISIBLE (-7425 760);
WIRE 16 -1 (-7250 1125)(-6825 1125);
FORCEPROP 2 LAST SIG_NAME LED_D5_R
J 0
(-7185 1160);
DISPLAY 0.553191 (-7185 1160);
FORCEPROP 2 LASTPROP $XRERR UNIQUE?
J 0
(-7425 1160);
DISPLAY 0.638298 (-7425 1160);
PAINT MONO (-7425 1160);
DISPLAY INVISIBLE (-7425 1160);
WIRE 16 -1 (-8125 2200)(-8125 1950);
WIRE 16 -1 (-8225 2200)(-8125 2200);
WIRE 16 -1 (-8125 1950)(-9300 1950);
FORCEPROP 2 LAST SIG_NAME FM_LED_D3
J 0
(-9310 1985);
DISPLAY 0.553191 (-9310 1985);
WIRE 16 -1 (-8825 1125)(-9275 1125);
FORCEPROP 2 LAST SIG_NAME FM_LED_D4
J 0
(-9310 1185);
DISPLAY 0.553191 (-9310 1185);
WIRE 16 -1 (-8950 2350)(-8950 2250);
WIRE 16 -1 (-7975 2350)(-8950 2350);
WIRE 16 -1 (-8950 2250)(-8825 2250);
WIRE 16 -1 (-7975 2450)(-7975 2350);
WIRE 16 -1 (-7575 2450)(-7975 2450);
FORCEPROP 2 LAST SIG_NAME LED_D2
J 0
(-7935 2485);
DISPLAY 0.553191 (-7935 2485);
FORCEPROP 2 LASTPROP $XRERR UNIQUE?
J 0
(-8175 2485);
DISPLAY 0.638298 (-8175 2485);
PAINT MONO (-8175 2485);
DISPLAY INVISIBLE (-8175 2485);
WIRE 16 -1 (-9300 2400)(-8125 2400);
FORCEPROP 2 LAST SIG_NAME FM_LED_D1
J 0
(-9310 2460);
DISPLAY 0.553191 (-9310 2460);
WIRE 16 -1 (-8125 2650)(-8125 2400);
WIRE 16 -1 (-8250 2650)(-8125 2650);
WIRE 16 -1 (-8825 2200)(-9300 2200);
FORCEPROP 2 LAST SIG_NAME FM_LED_D2
J 0
(-9310 2260);
DISPLAY 0.553191 (-9310 2260);
WIRE 16 -1 (-7275 2250)(-6850 2250);
FORCEPROP 2 LAST SIG_NAME LED_D3_R
J 0
(-7210 2285);
DISPLAY 0.553191 (-7210 2285);
FORCEPROP 2 LASTPROP $XRERR UNIQUE?
J 0
(-7450 2285);
DISPLAY 0.638298 (-7450 2285);
PAINT MONO (-7450 2285);
DISPLAY INVISIBLE (-7450 2285);
WIRE 16 -1 (-7975 2650)(-7975 2700);
FORCEPROP 2 LAST SIG_NAME LED_D1
J 0
(-7935 2685);
DISPLAY 0.553191 (-7935 2685);
FORCEPROP 2 LASTPROP $XRERR UNIQUE?
J 0
(-8175 2685);
DISPLAY 0.638298 (-8175 2685);
PAINT MONO (-8175 2685);
DISPLAY INVISIBLE (-8175 2685);
WIRE 16 -1 (-7575 2650)(-7975 2650);
WIRE 16 -1 (-7975 2700)(-8250 2700);
WIRE 16 -1 (-7250 1300)(-6825 1300);
FORCEPROP 2 LAST SIG_NAME LED_D4_R
J 0
(-7185 1335);
DISPLAY 0.553191 (-7185 1335);
FORCEPROP 2 LASTPROP $XRERR UNIQUE?
J 0
(-7425 1335);
DISPLAY 0.638298 (-7425 1335);
PAINT MONO (-7425 1335);
DISPLAY INVISIBLE (-7425 1335);
WIRE 16 -1 (-8100 675)(-8100 425);
WIRE 16 -1 (-8200 675)(-8100 675);
WIRE 16 -1 (-8100 425)(-9275 425);
FORCEPROP 2 LAST SIG_NAME FM_LED_D7
J 0
(-9310 460);
DISPLAY 0.553191 (-9310 460);
WIRE 16 -1 (-8225 2250)(-7575 2250);
FORCEPROP 2 LAST SIG_NAME LED_D3
J 0
(-7935 2285);
DISPLAY 0.553191 (-7935 2285);
FORCEPROP 2 LASTPROP $XRERR UNIQUE?
J 0
(-8175 2285);
DISPLAY 0.638298 (-8175 2285);
PAINT MONO (-8175 2285);
DISPLAY INVISIBLE (-8175 2285);
WIRE 16 -1 (-7275 2450)(-6850 2450);
FORCEPROP 2 LAST SIG_NAME LED_D2_R
J 0
(-7210 2485);
DISPLAY 0.553191 (-7210 2485);
FORCEPROP 2 LASTPROP $XRERR UNIQUE?
J 0
(-7450 2485);
DISPLAY 0.638298 (-7450 2485);
PAINT MONO (-7450 2485);
DISPLAY INVISIBLE (-7450 2485);
WIRE 16 -1 (-2800 5075)(-2100 5075);
FORCEPROP 2 LAST SIG_NAME PU_BOOT_RDY_LED
J 0
(-2685 5085);
DISPLAY 0.489362 (-2685 5085);
FORCEPROP 2 LASTPROP $XRERR UNIQUE?
J 0
(-2925 5085);
DISPLAY 0.638298 (-2925 5085);
PAINT MONO (-2925 5085);
DISPLAY INVISIBLE (-2925 5085);
WIRE 16 -1 (-2950 3450)(-2350 3450);
FORCEPROP 2 LAST SIG_NAME PU_SMERR_LED
J 0
(-2860 3460);
DISPLAY 0.489362 (-2860 3460);
FORCEPROP 2 LASTPROP $XRERR UNIQUE?
J 0
(-3100 3460);
DISPLAY 0.638298 (-3100 3460);
PAINT MONO (-3100 3460);
DISPLAY INVISIBLE (-3100 3460);
WIRE 16 -1 (-3975 1975)(-3225 1975);
WIRE 16 -1 (-4125 550)(-3375 550);
FORCEPROP 2 LAST SIG_NAME P5V_STBY_PWR_LED
J 0
(-4060 560);
DISPLAY 0.489362 (-4060 560);
FORCEPROP 2 LASTPROP $XRERR UNIQUE?
J 0
(-4300 560);
DISPLAY 0.638298 (-4300 560);
PAINT MONO (-4300 560);
DISPLAY INVISIBLE (-4300 560);
WIRE 16 -1 (-4250 3450)(-3250 3450);
FORCEPROP 2 LAST SIG_NAME SMERR_LED_N
J 0
(-3810 3460);
DISPLAY 0.489362 (-3810 3460);
FORCEPROP 2 LASTPROP $XRERR UNIQUE?
J 0
(-4050 3460);
DISPLAY 0.638298 (-4050 3460);
PAINT MONO (-4050 3460);
DISPLAY INVISIBLE (-4050 3460);
WIRE 16 -1 (-4100 5075)(-3100 5075);
FORCEPROP 2 LAST SIG_NAME BOOT_RDY_LED_N
J 0
(-3660 5085);
DISPLAY 0.489362 (-3660 5085);
FORCEPROP 2 LASTPROP $XRERR UNIQUE?
J 0
(-3900 5085);
DISPLAY 0.638298 (-3900 5085);
PAINT MONO (-3900 5085);
DISPLAY INVISIBLE (-3900 5085);
WIRE 16 -1 (-4700 5125)(-4950 5125);
WIRE 16 -1 (-4950 5125)(-4950 5325);
WIRE 16 -1 (-4950 5125)(-5575 5125);
FORCEPROP 2 LAST SIG_NAME BOOT_RDY_BUF_LED
J 0
(-5510 5135);
DISPLAY 0.489362 (-5510 5135);
FORCEPROP 2 LASTPROP $XRERR UNIQUE?
J 0
(-5750 5135);
DISPLAY 0.638298 (-5750 5135);
PAINT MONO (-5750 5135);
DISPLAY INVISIBLE (-5750 5135);
WIRE 16 -1 (-4100 5125)(-3950 5125);
WIRE 16 -1 (-3950 5125)(-3950 5325);
WIRE 16 -1 (-3950 5125)(-3950 4850);
WIRE 16 -1 (-4725 4850)(-3950 4850);
FORCEPROP 2 LAST SIG_NAME BOOT_RDY_LED
J 0
(-4510 4860);
DISPLAY 0.489362 (-4510 4860);
FORCEPROP 2 LASTPROP $XRERR UNIQUE?
J 0
(-4750 4860);
DISPLAY 0.638298 (-4750 4860);
PAINT MONO (-4750 4860);
DISPLAY INVISIBLE (-4750 4860);
WIRE 16 -1 (-4725 4850)(-4725 5075);
WIRE 16 -1 (-4725 5075)(-4700 5075);
WIRE 16 -1 (-7850 5125)(-7600 5125);
WIRE 16 -1 (-6775 5125)(-7600 5125);
FORCEPROP 2 LAST SIG_NAME BOOT_RDY_R1_N
J 0
(-7385 5135);
DISPLAY 0.489362 (-7385 5135);
FORCEPROP 2 LASTPROP $XRERR UNIQUE?
J 0
(-7625 5135);
DISPLAY 0.638298 (-7625 5135);
PAINT MONO (-7625 5135);
DISPLAY INVISIBLE (-7625 5135);
WIRE 16 -1 (-7600 4875)(-7600 5125);
WIRE 16 -1 (-7600 4875)(-7850 4875);
WIRE 16 -1 (-4850 1775)(-4850 1975);
WIRE 16 -1 (-4850 1975)(-4275 1975);
FORCEPROP 2 LAST SIG_NAME P12V_ALL_PWROK_N
J 0
(-4785 2010);
DISPLAY 0.489362 (-4785 2010);
FORCEPROP 2 LASTPROP $XRERR UNIQUE?
J 0
(-5025 2010);
DISPLAY 0.638298 (-5025 2010);
PAINT MONO (-5025 2010);
DISPLAY INVISIBLE (-5025 2010);
WIRE 16 -1 (-5050 1575)(-5825 1575);
FORCEPROP 2 LAST SIG_NAME P12V_ALL_PWROK
J 0
(-5735 1610);
DISPLAY 0.489362 (-5735 1610);
WIRE 16 -1 (-5925 3500)(-6575 3500);
FORCEPROP 2 LAST SIG_NAME FM_SMERR_BUF_LED_N
J 0
(-6385 3540);
DISPLAY 0.489362 (-6385 3540);
FORCEPROP 2 LASTPROP $XRERR UNIQUE?
J 0
(-6625 3540);
DISPLAY 0.638298 (-6625 3540);
PAINT MONO (-6625 3540);
DISPLAY INVISIBLE (-6625 3540);
WIRE 16 -1 (-8050 5125)(-8975 5125);
FORCEPROP 2 LAST SIG_NAME FM_BIOS_POST_CMPLT_N
J 0
(-8860 5135);
DISPLAY 0.489362 (-8860 5135);
WIRE 16 -1 (-8050 4875)(-8650 4875);
FORCEPROP 2 LAST SIG_NAME BOOT_RDY_H
J 0
(-8610 4885);
DISPLAY 0.489362 (-8610 4885);
WIRE 16 -1 (-9625 4675)(-9625 4700);
WIRE 16 -1 (-5775 5125)(-6425 5125);
FORCEPROP 2 LAST SIG_NAME BOOT_RDY_BUF_R_LED
J 0
(-6310 5150);
DISPLAY 0.489362 (-6310 5150);
FORCEPROP 2 LASTPROP $XRERR UNIQUE?
J 0
(-6550 5150);
DISPLAY 0.638298 (-6550 5150);
PAINT MONO (-6550 5150);
DISPLAY INVISIBLE (-6550 5150);
WIRE 16 -1 (-5725 3500)(-5100 3500);
WIRE 16 -1 (-5100 3500)(-5100 3700);
WIRE 16 -1 (-4850 3500)(-5100 3500);
WIRE 16 -1 (-6925 3500)(-8500 3500);
FORCEPROP 2 LAST SIG_NAME FM_SMERR_LED_N
J 0
(-8275 3510);
DISPLAY 0.489362 (-8275 3510);
WIRE 16 -1 (-4250 3500)(-4100 3500);
WIRE 16 -1 (-4100 3500)(-4100 3700);
WIRE 16 -1 (-4100 3500)(-4100 3225);
WIRE 16 -1 (-4875 3225)(-4100 3225);
FORCEPROP 2 LAST SIG_NAME SMERR_LED
J 0
(-4560 3235);
DISPLAY 0.489362 (-4560 3235);
FORCEPROP 2 LASTPROP $XRERR UNIQUE?
J 0
(-4800 3235);
DISPLAY 0.638298 (-4800 3235);
PAINT MONO (-4800 3235);
DISPLAY INVISIBLE (-4800 3235);
WIRE 16 -1 (-4875 3225)(-4875 3450);
WIRE 16 -1 (-4875 3450)(-4850 3450);
WIRE 16 -1 (-8850 2650)(-9300 2650);
FORCEPROP 2 LAST SIG_NAME FM_LED_D0
J 0
(-9310 2710);
DISPLAY 0.553191 (-9310 2710);
WIRE 16 -1 (-8800 675)(-9275 675);
FORCEPROP 2 LAST SIG_NAME FM_LED_D6
J 0
(-9310 735);
DISPLAY 0.553191 (-9310 735);
DOT 1 (-6400 925);
DOT 1 (-6400 1125);
DOT 1 (-6425 2650);
DOT 1 (-6425 2450);
DOT 1 (-5100 3500);
DOT 1 (-7350 3975);
DOT 1 (-4100 3500);
DOT 1 (-7600 5125);
DOT 1 (-7200 5600);
DOT 1 (-4950 5125);
DOT 1 (-3950 5125);
DOT 1 (-6425 2825);
DOT 1 (-8050 625);
DOT 1 (-8075 2150);
DOT 1 (-6400 1300);
FORCENOTE
P12V POWER LED
(-3050 2675) 0;
DISPLAY LEFT (-3050 2675);
DISPLAY 2.000000 (-3050 2675);
FORCENOTE
SMERR LED
(-3150 4300) 0;
DISPLAY LEFT (-3150 4300);
DISPLAY 2.000000 (-3150 4300);
FORCENOTE
P5V_STBY POWER LED
(-3125 1325) 0;
DISPLAY LEFT (-3125 1325);
DISPLAY 2.000000 (-3125 1325);
FORCENOTE
BOOT-UP READY LED
(-3325 6100) 0;
DISPLAY LEFT (-3325 6100);
DISPLAY 2.000000 (-3325 6100);
QUIT
